FILE_TYPE = MACRO_DRAWING;
SET COLOR_WIRE YELLOW;
SET COLOR_PROP ORANGE;
SET COLOR_DOT WHITE;
SET COLOR_ARC YELLOW;
SET COLOR_BODY GREEN;
SET COLOR_NOTE PURPLE;
SET PROP_DISPLAY VALUE;
SET PAGE_NUMBER P331;
FORCEADD OFFPAGE..4
R 2
(-2250 2100);
FORCEPROP 2 LAST $XR0 115 
J 0
(-2502 2100);
DISPLAY 0.638298 (-2502 2100);
PAINT MONO (-2502 2100);
FORCEPROP 2 LAST CDS_LIB standard
J 0
(-2250 2100);
DISPLAY INVISIBLE (-2250 2100);
FORCEPROP 1 LAST OFFPAGE TRUE
J 2
(-2575 1975);
DISPLAY 0.872340 (-2575 1975);
PAINT GREEN (-2575 1975);
DISPLAY INVISIBLE (-2575 1975);
FORCEPROP 1 LAST COMMENT_BODY TRUE
J 2
(-2225 2000);
DISPLAY 0.872340 (-2225 2000);
PAINT GREEN (-2225 2000);
DISPLAY INVISIBLE (-2225 2000);
FORCEPROP 2 LAST PATH I1
J 0
(-2525 2150);
DISPLAY 1.021277 (-2525 2150);
DISPLAY INVISIBLE (-2525 2150);
FORCEADD UNIVERSAL_POWER..1
(-1975 4075);
FORCEPROP 3 LASTPIN (-1975 4025) SIG_NAME P3V3_AUX\g
J 0
(-1965 4035);
DISPLAY 0.659574 (-1965 4035);
PAINT MONO (-1965 4035);
DISPLAY INVISIBLE (-1965 4035);
FORCEPROP 1 LAST HDL_POWER P3V3_AUX
J 1
(-1975 4125);
DISPLAY 0.872340 (-1975 4125);
PAINT GREEN (-1975 4125);
FORCEPROP 2 LAST CDS_LIB pure_quanta_power
J 0
(-1975 4075);
PAINT MONO (-1975 4075);
DISPLAY INVISIBLE (-1975 4075);
FORCEPROP 1 LAST PATH I10
J 0
(-1925 4100);
DISPLAY 0.872340 (-1925 4100);
PAINT AQUA (-1925 4100);
DISPLAY INVISIBLE (-1925 4100);
FORCEADD UNIVERSAL_GND..1
(5175 4775);
FORCEPROP 3 LASTPIN (5175 4825) SIG_NAME GND\g
J 0
(5185 4835);
DISPLAY 0.659574 (5185 4835);
PAINT MONO (5185 4835);
DISPLAY INVISIBLE (5185 4835);
FORCEPROP 2 LAST CDS_LIB pure_quanta_power
J 0
(5175 4775);
DISPLAY INVISIBLE (5175 4775);
FORCEPROP 1 LAST HDL_POWER GND
J 1
(5200 4700);
DISPLAY 0.872340 (5200 4700);
PAINT GREEN (5200 4700);
DISPLAY INVISIBLE (5200 4700);
FORCEPROP 1 LAST PATH I100
J 0
(5250 4775);
DISPLAY 0.872340 (5250 4775);
PAINT AQUA (5250 4775);
DISPLAY INVISIBLE (5250 4775);
FORCEADD UNIVERSAL_GND..1
(4000 4000);
FORCEPROP 3 LASTPIN (4000 4050) SIG_NAME GND\g
J 0
(4010 4060);
DISPLAY 0.659574 (4010 4060);
PAINT MONO (4010 4060);
DISPLAY INVISIBLE (4010 4060);
FORCEPROP 2 LAST CDS_LIB pure_quanta_power
J 0
(4000 4000);
DISPLAY INVISIBLE (4000 4000);
FORCEPROP 1 LAST HDL_POWER GND
J 1
(4025 3925);
DISPLAY 0.872340 (4025 3925);
PAINT GREEN (4025 3925);
DISPLAY INVISIBLE (4025 3925);
FORCEPROP 1 LAST PATH I101
J 0
(4075 4000);
DISPLAY 0.872340 (4075 4000);
PAINT AQUA (4075 4000);
DISPLAY INVISIBLE (4075 4000);
FORCEADD UNIVERSAL_GND..1
(3300 4225);
FORCEPROP 3 LASTPIN (3300 4275) SIG_NAME GND\g
J 0
(3310 4285);
DISPLAY 0.659574 (3310 4285);
PAINT MONO (3310 4285);
DISPLAY INVISIBLE (3310 4285);
FORCEPROP 2 LAST CDS_LIB pure_quanta_power
J 0
(3300 4225);
DISPLAY INVISIBLE (3300 4225);
FORCEPROP 1 LAST HDL_POWER GND
J 1
(3325 4150);
DISPLAY 0.872340 (3325 4150);
PAINT GREEN (3325 4150);
DISPLAY INVISIBLE (3325 4150);
FORCEPROP 1 LAST PATH I102
J 0
(3375 4225);
DISPLAY 0.872340 (3375 4225);
PAINT AQUA (3375 4225);
DISPLAY INVISIBLE (3375 4225);
FORCEADD Q_RES..1
(-650 6050);
FORCEPROP 1 LAST LOCATION R4569
J 0
(-925 6050);
DISPLAY 0.787234 (-925 6050);
FORCEPROP 0 LAST $SEC 1
J 0
(-400 6175);
DISPLAY 0.680851 (-400 6175);
PAINT MONO (-400 6175);
DISPLAY INVISIBLE (-400 6175);
FORCEPROP 0 LAST CDS_SEC 1
J 0
(-400 6175);
DISPLAY 1.021277 (-400 6175);
DISPLAY INVISIBLE (-400 6175);
FORCEPROP 1 LASTPIN (-750 6050) $PN 1
J 0
(-738 6062);
DISPLAY 0.787234 (-738 6062);
PAINT MONO (-738 6062);
FORCEPROP 1 LASTPIN (-550 6050) $PN 2
J 0
(-588 6062);
DISPLAY 0.787234 (-588 6062);
PAINT MONO (-588 6062);
FORCEPROP 1 LAST MATERIAL EMPTY
J 0
(-425 6050);
DISPLAY 0.510638 (-425 6050);
PAINT RED (-425 6050);
FORCEPROP 1 LAST WATTAGE 1/16W
J 2
(-400 6150);
DISPLAY 0.510638 (-400 6150);
FORCEPROP 1 LAST VALUE 0
J 2
(-525 6050);
DISPLAY 0.510638 (-525 6050);
FORCEPROP 1 LAST TOLERANCE 5%
J 0
(-500 6050);
DISPLAY 0.510638 (-500 6050);
FORCEPROP 1 LAST PACK_TYPE 0402LF
J 0
(-750 6150);
DISPLAY 0.510638 (-750 6150);
FORCEPROP 2 LAST CDS_LIB pure_quanta
J 0
(-650 6050);
DISPLAY INVISIBLE (-650 6050);
FORCEPROP 1 LAST PATH I107
J 0
(-700 6200);
DISPLAY 0.978723 (-700 6200);
PAINT WHITE (-700 6200);
DISPLAY INVISIBLE (-700 6200);
FORCEPROP 1 LAST PART_NUMBER CS00002JB13
J 0
(-700 6100);
DISPLAY 0.510638 (-700 6100);
DISPLAY INVISIBLE (-700 6100);
FORCEADD Q_RES..1
(-425 3125);
FORCEPROP 1 LAST LOCATION R4571
J 0
(-675 3125);
DISPLAY 0.787234 (-675 3125);
FORCEPROP 0 LAST $SEC 1
J 0
(-175 3250);
DISPLAY 0.680851 (-175 3250);
PAINT MONO (-175 3250);
DISPLAY INVISIBLE (-175 3250);
FORCEPROP 0 LAST CDS_SEC 1
J 0
(-175 3250);
DISPLAY 1.021277 (-175 3250);
DISPLAY INVISIBLE (-175 3250);
FORCEPROP 1 LASTPIN (-525 3125) $PN 1
J 0
(-513 3137);
DISPLAY 0.787234 (-513 3137);
PAINT MONO (-513 3137);
FORCEPROP 1 LASTPIN (-325 3125) $PN 2
J 0
(-363 3137);
DISPLAY 0.787234 (-363 3137);
PAINT MONO (-363 3137);
FORCEPROP 1 LAST VALUE 0
J 2
(-300 3125);
DISPLAY 0.510638 (-300 3125);
FORCEPROP 1 LAST TOLERANCE 5%
J 0
(-275 3125);
DISPLAY 0.510638 (-275 3125);
FORCEPROP 1 LAST MATERIAL EMPTY
J 0
(-200 3125);
DISPLAY 0.510638 (-200 3125);
PAINT RED (-200 3125);
FORCEPROP 1 LAST WATTAGE 1/16W
J 2
(-175 3225);
DISPLAY 0.510638 (-175 3225);
FORCEPROP 1 LAST PACK_TYPE 0402LF
J 0
(-525 3225);
DISPLAY 0.510638 (-525 3225);
FORCEPROP 2 LAST CDS_LIB pure_quanta
J 0
(-425 3125);
DISPLAY INVISIBLE (-425 3125);
FORCEPROP 1 LAST PATH I108
J 0
(-475 3275);
DISPLAY 0.978723 (-475 3275);
PAINT WHITE (-475 3275);
DISPLAY INVISIBLE (-475 3275);
FORCEPROP 1 LAST PART_NUMBER CS00002JB13
J 0
(-475 3175);
DISPLAY 0.510638 (-475 3175);
DISPLAY INVISIBLE (-475 3175);
FORCEADD Q_RES..1
(-425 4575);
FORCEPROP 1 LAST LOCATION R4570
J 0
(-675 4575);
DISPLAY 0.787234 (-675 4575);
FORCEPROP 0 LAST $SEC 1
J 0
(-175 4700);
DISPLAY 0.680851 (-175 4700);
PAINT MONO (-175 4700);
DISPLAY INVISIBLE (-175 4700);
FORCEPROP 0 LAST CDS_SEC 1
J 0
(-175 4700);
DISPLAY 1.021277 (-175 4700);
DISPLAY INVISIBLE (-175 4700);
FORCEPROP 1 LASTPIN (-525 4575) $PN 1
J 0
(-513 4587);
DISPLAY 0.787234 (-513 4587);
PAINT MONO (-513 4587);
FORCEPROP 1 LASTPIN (-325 4575) $PN 2
J 0
(-363 4587);
DISPLAY 0.787234 (-363 4587);
PAINT MONO (-363 4587);
FORCEPROP 1 LAST VALUE 0
J 2
(-300 4575);
DISPLAY 0.510638 (-300 4575);
FORCEPROP 1 LAST TOLERANCE 5%
J 0
(-275 4575);
DISPLAY 0.510638 (-275 4575);
FORCEPROP 1 LAST MATERIAL EMPTY
J 0
(-200 4575);
DISPLAY 0.510638 (-200 4575);
PAINT RED (-200 4575);
FORCEPROP 1 LAST PACK_TYPE 0402LF
J 0
(-525 4675);
DISPLAY 0.510638 (-525 4675);
FORCEPROP 1 LAST WATTAGE 1/16W
J 2
(-175 4675);
DISPLAY 0.510638 (-175 4675);
FORCEPROP 2 LAST CDS_LIB pure_quanta
J 0
(-425 4575);
DISPLAY INVISIBLE (-425 4575);
FORCEPROP 1 LAST PATH I109
J 0
(-475 4725);
DISPLAY 0.978723 (-475 4725);
PAINT WHITE (-475 4725);
DISPLAY INVISIBLE (-475 4725);
FORCEPROP 1 LAST PART_NUMBER CS00002JB13
J 0
(-475 4625);
DISPLAY 0.510638 (-475 4625);
DISPLAY INVISIBLE (-475 4625);
FORCEADD UNIVERSAL_GND..1
(-1975 4450);
FORCEPROP 3 LASTPIN (-1975 4500) SIG_NAME GND\g
J 0
(-1965 4510);
DISPLAY 0.659574 (-1965 4510);
PAINT MONO (-1965 4510);
DISPLAY INVISIBLE (-1965 4510);
FORCEPROP 2 LAST CDS_LIB pure_quanta_power
J 0
(-1975 4450);
DISPLAY INVISIBLE (-1975 4450);
FORCEPROP 1 LAST HDL_POWER GND
J 1
(-1950 4375);
DISPLAY 0.872340 (-1950 4375);
PAINT GREEN (-1950 4375);
DISPLAY INVISIBLE (-1950 4375);
FORCEPROP 1 LAST PATH I11
J 0
(-1900 4450);
DISPLAY 0.872340 (-1900 4450);
PAINT AQUA (-1900 4450);
DISPLAY INVISIBLE (-1900 4450);
FORCEADD Q_RES..2
R 2
(325 1250);
FORCEPROP 1 LAST LOCATION R4546
J 2
(280 1375);
DISPLAY 0.638298 (280 1375);
FORCEPROP 0 LAST $SEC 1
J 0
(300 1425);
DISPLAY 0.680851 (300 1425);
PAINT MONO (300 1425);
DISPLAY INVISIBLE (300 1425);
FORCEPROP 0 LAST CDS_SEC 1
J 0
(300 1425);
DISPLAY 0.680851 (300 1425);
DISPLAY INVISIBLE (300 1425);
FORCEPROP 1 LASTPIN (325 1350) $PN 1
J 2
(320 1312);
DISPLAY 0.787234 (320 1312);
PAINT MONO (320 1312);
FORCEPROP 1 LASTPIN (325 1150) $PN 2
J 2
(320 1160);
DISPLAY 0.787234 (320 1160);
PAINT MONO (320 1160);
FORCEPROP 1 LAST VALUE 100K
J 2
(280 1325);
DISPLAY 0.638298 (280 1325);
FORCEPROP 1 LAST PACK_TYPE 0402LF
J 2
(285 1075);
DISPLAY 0.638298 (285 1075);
FORCEPROP 1 LAST MATERIAL EMPTY
J 2
(285 1175);
DISPLAY 0.638298 (285 1175);
FORCEPROP 1 LAST WATTAGE 1/16W
J 2
(285 1225);
DISPLAY 0.638298 (285 1225);
FORCEPROP 1 LAST TOLERANCE 1%
J 2
(280 1275);
DISPLAY 0.638298 (280 1275);
FORCEPROP 2 LAST CDS_LIB pure_quanta
J 2
(325 1250);
DISPLAY INVISIBLE (325 1250);
FORCEPROP 1 LAST PATH I110
J 2
(275 1425);
DISPLAY 0.978723 (275 1425);
PAINT WHITE (275 1425);
DISPLAY INVISIBLE (275 1425);
FORCEPROP 1 LAST PART_NUMBER CS41002FB09
J 2
(285 1125);
DISPLAY 0.638298 (285 1125);
DISPLAY INVISIBLE (285 1125);
FORCEADD Q_CAP..1
(1100 775);
FORCEPROP 1 LAST LOCATION C6
J 0
(1150 875);
DISPLAY 0.638298 (1150 875);
FORCEPROP 0 LAST $SEC 1
J 0
(1150 925);
DISPLAY 0.680851 (1150 925);
PAINT MONO (1150 925);
DISPLAY INVISIBLE (1150 925);
FORCEPROP 0 LAST CDS_SEC 1
J 0
(1150 925);
DISPLAY 0.680851 (1150 925);
DISPLAY INVISIBLE (1150 925);
FORCEPROP 1 LASTPIN (1100 875) $PN 1
J 0
(1110 855);
DISPLAY 0.787234 (1110 855);
PAINT MONO (1110 855);
FORCEPROP 1 LASTPIN (1100 675) $PN 2
J 0
(1110 655);
DISPLAY 0.787234 (1110 655);
PAINT MONO (1110 655);
FORCEPROP 1 LAST VALUE 0.1UF
J 0
(1150 825);
DISPLAY 0.638298 (1150 825);
FORCEPROP 1 LAST TOLERANCE 10%
J 0
(1150 725);
DISPLAY 0.638298 (1150 725);
FORCEPROP 1 LAST VOLTAGE 25V
J 0
(1150 775);
DISPLAY 0.638298 (1150 775);
FORCEPROP 1 LAST PACK_TYPE 0402
J 0
(1150 575);
DISPLAY 0.638298 (1150 575);
FORCEPROP 1 LAST MATERIAL EMPTY
J 0
(1150 675);
DISPLAY 0.638298 (1150 675);
PAINT RED (1150 675);
FORCEPROP 2 LAST CDS_LIB pure_quanta
J 0
(1100 775);
DISPLAY INVISIBLE (1100 775);
FORCEPROP 1 LAST PATH I111
J 0
(1150 925);
DISPLAY 0.978723 (1150 925);
PAINT WHITE (1150 925);
DISPLAY INVISIBLE (1150 925);
FORCEPROP 1 LAST PART_NUMBER CH4104K1B00
J 0
(1150 625);
DISPLAY 0.638298 (1150 625);
DISPLAY INVISIBLE (1150 625);
FORCEADD OFFPAGE..4
R 2
(-2250 4925);
FORCEPROP 2 LAST $XR0 115 
J 0
(-2502 4925);
DISPLAY 0.638298 (-2502 4925);
PAINT MONO (-2502 4925);
FORCEPROP 2 LAST CDS_LIB standard
J 0
(-2250 4925);
DISPLAY INVISIBLE (-2250 4925);
FORCEPROP 1 LAST OFFPAGE TRUE
J 2
(-2575 4800);
DISPLAY 0.872340 (-2575 4800);
PAINT GREEN (-2575 4800);
DISPLAY INVISIBLE (-2575 4800);
FORCEPROP 1 LAST COMMENT_BODY TRUE
J 2
(-2225 4825);
DISPLAY 0.872340 (-2225 4825);
PAINT GREEN (-2225 4825);
DISPLAY INVISIBLE (-2225 4825);
FORCEPROP 2 LAST PATH I12
J 0
(-2525 4975);
DISPLAY 1.021277 (-2525 4975);
DISPLAY INVISIBLE (-2525 4975);
FORCEADD Q_RES..2
(-1975 4725);
FORCEPROP 1 LAST LOCATION R4159
J 0
(-1930 4850);
DISPLAY 0.978723 (-1930 4850);
FORCEPROP 0 LAST $SEC 1
J 0
(-1925 4900);
DISPLAY 0.680851 (-1925 4900);
PAINT MONO (-1925 4900);
DISPLAY INVISIBLE (-1925 4900);
FORCEPROP 0 LAST CDS_SEC 1
J 0
(-1925 4900);
DISPLAY 1.021277 (-1925 4900);
DISPLAY INVISIBLE (-1925 4900);
FORCEPROP 1 LASTPIN (-1975 4825) $PN 1
J 0
(-1970 4787);
DISPLAY 0.787234 (-1970 4787);
PAINT MONO (-1970 4787);
FORCEPROP 1 LASTPIN (-1975 4625) $PN 2
J 0
(-1970 4635);
DISPLAY 0.787234 (-1970 4635);
PAINT MONO (-1970 4635);
FORCEPROP 1 LAST WATTAGE 1/16W
J 0
(-1935 4700);
DISPLAY 0.510638 (-1935 4700);
FORCEPROP 1 LAST TOLERANCE 1%
J 0
(-1930 4750);
DISPLAY 0.510638 (-1930 4750);
FORCEPROP 1 LAST MATERIAL EMPTY
J 0
(-1935 4650);
DISPLAY 0.510638 (-1935 4650);
PAINT RED (-1935 4650);
FORCEPROP 1 LAST PACK_TYPE 0402LF
J 0
(-1935 4550);
DISPLAY 0.510638 (-1935 4550);
FORCEPROP 1 LAST VALUE 100K
J 0
(-1930 4800);
DISPLAY 0.510638 (-1930 4800);
FORCEPROP 2 LAST CDS_LIB pure_quanta
J 0
(-1975 4725);
DISPLAY INVISIBLE (-1975 4725);
FORCEPROP 1 LAST PATH I13
J 0
(-1925 4900);
DISPLAY 0.978723 (-1925 4900);
PAINT WHITE (-1925 4900);
DISPLAY INVISIBLE (-1925 4900);
FORCEPROP 1 LAST PART_NUMBER CS41002FB09
J 0
(-1935 4600);
DISPLAY 0.510638 (-1935 4600);
DISPLAY INVISIBLE (-1935 4600);
FORCEADD Q_RES..2
(-2000 5200);
FORCEPROP 1 LAST LOCATION R4158
J 0
(-1955 5325);
DISPLAY 0.978723 (-1955 5325);
FORCEPROP 0 LAST $SEC 1
J 0
(-1950 5375);
DISPLAY 0.680851 (-1950 5375);
PAINT MONO (-1950 5375);
DISPLAY INVISIBLE (-1950 5375);
FORCEPROP 0 LAST CDS_SEC 1
J 0
(-1950 5375);
DISPLAY 1.021277 (-1950 5375);
DISPLAY INVISIBLE (-1950 5375);
FORCEPROP 1 LASTPIN (-2000 5300) $PN 1
J 0
(-1995 5262);
DISPLAY 0.787234 (-1995 5262);
PAINT MONO (-1995 5262);
FORCEPROP 1 LASTPIN (-2000 5100) $PN 2
J 0
(-1995 5110);
DISPLAY 0.787234 (-1995 5110);
PAINT MONO (-1995 5110);
FORCEPROP 1 LAST TOLERANCE 1%
J 0
(-1955 5225);
DISPLAY 0.787234 (-1955 5225);
FORCEPROP 1 LAST MATERIAL EMPTY
J 0
(-1960 5125);
DISPLAY 0.787234 (-1960 5125);
PAINT RED (-1960 5125);
FORCEPROP 1 LAST VALUE 54.9K
J 0
(-1955 5275);
DISPLAY 0.787234 (-1955 5275);
FORCEPROP 1 LAST WATTAGE 1/16W
J 0
(-1960 5175);
DISPLAY 0.787234 (-1960 5175);
FORCEPROP 1 LAST PACK_TYPE 0402LF
J 0
(-1960 5025);
DISPLAY 0.787234 (-1960 5025);
FORCEPROP 2 LAST CDS_LIB pure_quanta
J 0
(-2000 5200);
DISPLAY INVISIBLE (-2000 5200);
FORCEPROP 1 LAST PATH I14
J 0
(-1950 5375);
DISPLAY 0.978723 (-1950 5375);
PAINT WHITE (-1950 5375);
DISPLAY INVISIBLE (-1950 5375);
FORCEPROP 1 LAST PART_NUMBER CS35492FB03
J 0
(-1960 5075);
DISPLAY 0.787234 (-1960 5075);
DISPLAY INVISIBLE (-1960 5075);
FORCEADD UNIVERSAL_POWER..1
(-2000 5450);
FORCEPROP 3 LASTPIN (-2000 5400) SIG_NAME P3V3_AUX\g
J 0
(-1990 5410);
DISPLAY 0.659574 (-1990 5410);
PAINT MONO (-1990 5410);
DISPLAY INVISIBLE (-1990 5410);
FORCEPROP 1 LAST HDL_POWER P3V3_AUX
J 1
(-2000 5500);
DISPLAY 0.872340 (-2000 5500);
PAINT GREEN (-2000 5500);
FORCEPROP 2 LAST CDS_LIB pure_quanta_power
J 0
(-2000 5450);
PAINT MONO (-2000 5450);
DISPLAY INVISIBLE (-2000 5450);
FORCEPROP 1 LAST PATH I15
J 0
(-1950 5475);
DISPLAY 0.872340 (-1950 5475);
PAINT AQUA (-1950 5475);
DISPLAY INVISIBLE (-1950 5475);
FORCEADD UNIVERSAL_GND..1
(-825 1775);
FORCEPROP 3 LASTPIN (-825 1825) SIG_NAME GND\g
J 0
(-815 1835);
DISPLAY 0.659574 (-815 1835);
PAINT MONO (-815 1835);
DISPLAY INVISIBLE (-815 1835);
FORCEPROP 2 LAST CDS_LIB pure_quanta_power
J 0
(-825 1775);
DISPLAY INVISIBLE (-825 1775);
FORCEPROP 1 LAST HDL_POWER GND
J 1
(-800 1700);
DISPLAY 0.872340 (-800 1700);
PAINT GREEN (-800 1700);
DISPLAY INVISIBLE (-800 1700);
FORCEPROP 1 LAST PATH I16
J 0
(-750 1775);
DISPLAY 0.872340 (-750 1775);
PAINT AQUA (-750 1775);
DISPLAY INVISIBLE (-750 1775);
FORCEADD MOSFET_NCH_DUAL..1
(-875 2150);
FORCEPROP 1 LAST LOCATION Q136
J 0
(-724 2124);
DISPLAY 0.723404 (-724 2124);
PAINT GREEN (-724 2124);
FORCEPROP 0 LAST $SEC 1
J 0
(-700 2275);
DISPLAY 0.680851 (-700 2275);
PAINT MONO (-700 2275);
DISPLAY INVISIBLE (-700 2275);
FORCEPROP 2 LAST CDS_SEC 1
J 0
(-700 2275);
DISPLAY 1.021277 (-700 2275);
DISPLAY INVISIBLE (-700 2275);
FORCEPROP 0 LASTPIN (-825 2350) $PN 6
R 1
J 0
(-835 2360);
DISPLAY 0.680851 (-835 2360);
PAINT MONO (-835 2360);
FORCEPROP 0 LASTPIN (-1075 2100) $PN 2
J 2
(-1085 2110);
DISPLAY 0.680851 (-1085 2110);
PAINT MONO (-1085 2110);
FORCEPROP 0 LASTPIN (-825 1950) $PN 1
R 1
J 2
(-835 1940);
DISPLAY 0.680851 (-835 1940);
PAINT MONO (-835 1940);
FORCEPROP 1 LAST MATERIAL IC
J 0
(-724 1999);
DISPLAY 0.723404 (-724 1999);
PAINT GREEN (-724 1999);
FORCEPROP 2 LAST VALUE PJT138K
J 0
(-700 2175);
DISPLAY 1.021277 (-700 2175);
FORCEPROP 2 LAST PART_TYPE SMLF
J 0
(-700 2225);
DISPLAY 1.021277 (-700 2225);
FORCEPROP 2 LAST CDS_LIB pure_quanta
J 0
(-875 2150);
DISPLAY INVISIBLE (-875 2150);
FORCEPROP 1 LAST NEEDS_NO_SIZE TRUE
J 0
(-875 2149);
DISPLAY 0.468085 (-875 2149);
PAINT GREEN (-875 2149);
DISPLAY INVISIBLE (-875 2149);
FORCEPROP 1 LAST CDS_LMAN_SYM_OUTLINE -150,150,150,-150
J 0
(-875 2150);
DISPLAY 0.468085 (-875 2150);
PAINT GREEN (-875 2150);
DISPLAY INVISIBLE (-875 2150);
FORCEPROP 1 LAST PATH I17
J 0
(-875 2150);
DISPLAY 0.723404 (-875 2150);
PAINT GREEN (-875 2150);
DISPLAY INVISIBLE (-875 2150);
FORCEPROP 1 LAST PART_NUMBER BAM138K0003
J 0
(-724 2064);
DISPLAY 0.723404 (-724 2064);
PAINT GREEN (-724 2064);
DISPLAY INVISIBLE (-724 2064);
FORCEADD Q_RES..2
(-825 2750);
FORCEPROP 1 LAST LOCATION R4165
J 0
(-780 2875);
DISPLAY 0.638298 (-780 2875);
FORCEPROP 2 LAST $SEC 1
J 0
(-775 2975);
DISPLAY 0.680851 (-775 2975);
PAINT MONO (-775 2975);
DISPLAY INVISIBLE (-775 2975);
FORCEPROP 2 LAST CDS_SEC 1
J 0
(-775 2975);
DISPLAY 1.021277 (-775 2975);
DISPLAY INVISIBLE (-775 2975);
FORCEPROP 1 LASTPIN (-825 2850) $PN 1
J 0
(-820 2812);
DISPLAY 0.787234 (-820 2812);
FORCEPROP 1 LASTPIN (-825 2650) $PN 2
J 0
(-820 2660);
DISPLAY 0.787234 (-820 2660);
FORCEPROP 1 LAST TOLERANCE 5%
J 0
(-780 2775);
DISPLAY 0.638298 (-780 2775);
FORCEPROP 1 LAST VALUE 4.7K
J 0
(-780 2825);
DISPLAY 0.638298 (-780 2825);
FORCEPROP 1 LAST WATTAGE 1/16W
J 0
(-785 2725);
DISPLAY 0.638298 (-785 2725);
FORCEPROP 1 LAST MATERIAL CHIP
J 0
(-785 2675);
DISPLAY 0.638298 (-785 2675);
FORCEPROP 1 LAST PACK_TYPE 0402LF
J 0
(-785 2625);
DISPLAY 0.638298 (-785 2625);
FORCEPROP 2 LAST CDS_LIB pure_quanta
J 0
(-825 2750);
PAINT MONO (-825 2750);
DISPLAY INVISIBLE (-825 2750);
FORCEPROP 1 LAST PATH I18
J 0
(-775 2925);
DISPLAY 0.978723 (-775 2925);
PAINT WHITE (-775 2925);
DISPLAY INVISIBLE (-775 2925);
FORCEPROP 1 LAST PART_NUMBER CS24702JB10
J 0
(-785 2575);
DISPLAY 0.638298 (-785 2575);
DISPLAY INVISIBLE (-785 2575);
FORCEADD UNIVERSAL_POWER..1
(-825 2975);
FORCEPROP 3 LASTPIN (-825 2925) SIG_NAME P3V3_AUX\g
J 0
(-815 2935);
DISPLAY 0.659574 (-815 2935);
PAINT MONO (-815 2935);
DISPLAY INVISIBLE (-815 2935);
FORCEPROP 1 LAST HDL_POWER P3V3_AUX
J 1
(-825 3025);
DISPLAY 0.872340 (-825 3025);
PAINT GREEN (-825 3025);
FORCEPROP 2 LAST CDS_LIB pure_quanta_power
J 0
(-825 2975);
PAINT MONO (-825 2975);
DISPLAY INVISIBLE (-825 2975);
FORCEPROP 1 LAST PATH I19
J 0
(-775 3000);
DISPLAY 0.872340 (-775 3000);
PAINT AQUA (-775 3000);
DISPLAY INVISIBLE (-775 3000);
FORCEADD Q_RES..2
(-1975 1900);
FORCEPROP 1 LAST LOCATION R4161
J 0
(-1930 2025);
DISPLAY 0.978723 (-1930 2025);
FORCEPROP 0 LAST $SEC 1
J 0
(-1925 2075);
DISPLAY 0.680851 (-1925 2075);
PAINT MONO (-1925 2075);
DISPLAY INVISIBLE (-1925 2075);
FORCEPROP 0 LAST CDS_SEC 1
J 0
(-1925 2075);
DISPLAY 1.021277 (-1925 2075);
DISPLAY INVISIBLE (-1925 2075);
FORCEPROP 1 LASTPIN (-1975 2000) $PN 1
J 0
(-1970 1962);
DISPLAY 0.787234 (-1970 1962);
PAINT MONO (-1970 1962);
FORCEPROP 1 LASTPIN (-1975 1800) $PN 2
J 0
(-1970 1810);
DISPLAY 0.787234 (-1970 1810);
PAINT MONO (-1970 1810);
FORCEPROP 1 LAST MATERIAL EMPTY
J 0
(-1935 1825);
DISPLAY 0.510638 (-1935 1825);
PAINT RED (-1935 1825);
FORCEPROP 1 LAST PACK_TYPE 0402LF
J 0
(-1935 1725);
DISPLAY 0.510638 (-1935 1725);
FORCEPROP 1 LAST TOLERANCE 1%
J 0
(-1930 1925);
DISPLAY 0.510638 (-1930 1925);
FORCEPROP 1 LAST VALUE 100K
J 0
(-1930 1975);
DISPLAY 0.510638 (-1930 1975);
FORCEPROP 1 LAST WATTAGE 1/16W
J 0
(-1935 1875);
DISPLAY 0.510638 (-1935 1875);
FORCEPROP 2 LAST CDS_LIB pure_quanta
J 0
(-1975 1900);
DISPLAY INVISIBLE (-1975 1900);
FORCEPROP 1 LAST PATH I2
J 0
(-1925 2075);
DISPLAY 0.978723 (-1925 2075);
PAINT WHITE (-1925 2075);
DISPLAY INVISIBLE (-1925 2075);
FORCEPROP 1 LAST PART_NUMBER CS41002FB09
J 0
(-1935 1775);
DISPLAY 0.510638 (-1935 1775);
DISPLAY INVISIBLE (-1935 1775);
FORCEADD UNIVERSAL_GND..1
(-800 3225);
FORCEPROP 3 LASTPIN (-800 3275) SIG_NAME GND\g
J 0
(-790 3285);
DISPLAY 0.659574 (-790 3285);
PAINT MONO (-790 3285);
DISPLAY INVISIBLE (-790 3285);
FORCEPROP 2 LAST CDS_LIB pure_quanta_power
J 0
(-800 3225);
DISPLAY INVISIBLE (-800 3225);
FORCEPROP 1 LAST HDL_POWER GND
J 1
(-775 3150);
DISPLAY 0.872340 (-775 3150);
PAINT GREEN (-775 3150);
DISPLAY INVISIBLE (-775 3150);
FORCEPROP 1 LAST PATH I20
J 0
(-725 3225);
DISPLAY 0.872340 (-725 3225);
PAINT AQUA (-725 3225);
DISPLAY INVISIBLE (-725 3225);
FORCEADD MOSFET_NCH_DUAL..1
(-850 3600);
FORCEPROP 1 LAST LOCATION Q137
J 0
(-699 3574);
DISPLAY 0.723404 (-699 3574);
PAINT GREEN (-699 3574);
FORCEPROP 0 LAST $SEC 1
J 0
(-675 3725);
DISPLAY 0.680851 (-675 3725);
PAINT MONO (-675 3725);
DISPLAY INVISIBLE (-675 3725);
FORCEPROP 2 LAST CDS_SEC 1
J 0
(-675 3725);
DISPLAY 1.021277 (-675 3725);
DISPLAY INVISIBLE (-675 3725);
FORCEPROP 0 LASTPIN (-800 3800) $PN 6
R 1
J 0
(-810 3810);
DISPLAY 0.680851 (-810 3810);
PAINT MONO (-810 3810);
FORCEPROP 0 LASTPIN (-1050 3550) $PN 2
J 2
(-1060 3560);
DISPLAY 0.680851 (-1060 3560);
PAINT MONO (-1060 3560);
FORCEPROP 0 LASTPIN (-800 3400) $PN 1
R 1
J 2
(-810 3390);
DISPLAY 0.680851 (-810 3390);
PAINT MONO (-810 3390);
FORCEPROP 2 LAST VALUE PJT138K
J 0
(-675 3625);
DISPLAY 1.021277 (-675 3625);
FORCEPROP 1 LAST MATERIAL IC
J 0
(-699 3449);
DISPLAY 0.723404 (-699 3449);
PAINT GREEN (-699 3449);
FORCEPROP 2 LAST PART_TYPE SMLF
J 0
(-675 3675);
DISPLAY 1.021277 (-675 3675);
FORCEPROP 2 LAST CDS_LIB pure_quanta
J 0
(-850 3600);
DISPLAY INVISIBLE (-850 3600);
FORCEPROP 1 LAST NEEDS_NO_SIZE TRUE
J 0
(-850 3599);
DISPLAY 0.468085 (-850 3599);
PAINT GREEN (-850 3599);
DISPLAY INVISIBLE (-850 3599);
FORCEPROP 1 LAST CDS_LMAN_SYM_OUTLINE -150,150,150,-150
J 0
(-850 3600);
DISPLAY 0.468085 (-850 3600);
PAINT GREEN (-850 3600);
DISPLAY INVISIBLE (-850 3600);
FORCEPROP 1 LAST PATH I21
J 0
(-850 3600);
DISPLAY 0.723404 (-850 3600);
PAINT GREEN (-850 3600);
DISPLAY INVISIBLE (-850 3600);
FORCEPROP 1 LAST PART_NUMBER BAM138K0003
J 0
(-699 3514);
DISPLAY 0.723404 (-699 3514);
PAINT GREEN (-699 3514);
DISPLAY INVISIBLE (-699 3514);
FORCEADD MOSFET_NCH_DUAL..2
(275 2450);
FORCEPROP 1 LAST LOCATION Q136
J 0
(426 2426);
DISPLAY 0.723404 (426 2426);
PAINT GREEN (426 2426);
FORCEPROP 0 LAST $SEC 2
J 0
(450 2575);
DISPLAY 0.680851 (450 2575);
PAINT MONO (450 2575);
DISPLAY INVISIBLE (450 2575);
FORCEPROP 0 LAST CDS_SEC 2
J 0
(450 2575);
DISPLAY 1.021277 (450 2575);
DISPLAY INVISIBLE (450 2575);
FORCEPROP 0 LASTPIN (325 2650) $PN 3
R 1
J 0
(315 2660);
DISPLAY 0.680851 (315 2660);
PAINT MONO (315 2660);
FORCEPROP 0 LASTPIN (75 2400) $PN 5
J 2
(65 2410);
DISPLAY 0.680851 (65 2410);
PAINT MONO (65 2410);
FORCEPROP 0 LASTPIN (325 2250) $PN 4
R 1
J 2
(315 2240);
DISPLAY 0.680851 (315 2240);
PAINT MONO (315 2240);
FORCEPROP 2 LAST PART_TYPE SMLF
J 0
(450 2525);
DISPLAY 1.021277 (450 2525);
FORCEPROP 2 LAST VALUE PJT138K
J 0
(450 2475);
DISPLAY 1.021277 (450 2475);
FORCEPROP 1 LAST MATERIAL IC
J 0
(426 2301);
DISPLAY 0.723404 (426 2301);
PAINT GREEN (426 2301);
FORCEPROP 1 LAST CDS_LMAN_SYM_OUTLINE -150,150,150,-150
J 0
(275 2450);
DISPLAY 0.468085 (275 2450);
PAINT GREEN (275 2450);
DISPLAY INVISIBLE (275 2450);
FORCEPROP 1 LAST NEEDS_NO_SIZE TRUE
J 0
(425 2341);
DISPLAY 0.468085 (425 2341);
PAINT GREEN (425 2341);
DISPLAY INVISIBLE (425 2341);
FORCEPROP 2 LAST CDS_LIB pure_quanta
J 0
(275 2450);
DISPLAY INVISIBLE (275 2450);
FORCEPROP 1 LAST PATH I22
J 0
(425 2300);
DISPLAY 0.723404 (425 2300);
PAINT GREEN (425 2300);
DISPLAY INVISIBLE (425 2300);
FORCEPROP 1 LAST PART_NUMBER BAM138K0003
J 0
(426 2356);
DISPLAY 0.723404 (426 2356);
PAINT GREEN (426 2356);
DISPLAY INVISIBLE (426 2356);
FORCEADD Q_RES..2
(-800 4200);
FORCEPROP 1 LAST LOCATION R4166
J 0
(-755 4325);
DISPLAY 0.638298 (-755 4325);
FORCEPROP 2 LAST $SEC 1
J 0
(-750 4425);
DISPLAY 0.680851 (-750 4425);
PAINT MONO (-750 4425);
DISPLAY INVISIBLE (-750 4425);
FORCEPROP 2 LAST CDS_SEC 1
J 0
(-750 4425);
DISPLAY 1.021277 (-750 4425);
DISPLAY INVISIBLE (-750 4425);
FORCEPROP 1 LASTPIN (-800 4300) $PN 1
J 0
(-795 4262);
DISPLAY 0.787234 (-795 4262);
FORCEPROP 1 LASTPIN (-800 4100) $PN 2
J 0
(-795 4110);
DISPLAY 0.787234 (-795 4110);
FORCEPROP 1 LAST TOLERANCE 5%
J 0
(-755 4225);
DISPLAY 0.638298 (-755 4225);
FORCEPROP 1 LAST PACK_TYPE 0402LF
J 0
(-760 4075);
DISPLAY 0.638298 (-760 4075);
FORCEPROP 1 LAST WATTAGE 1/16W
J 0
(-760 4175);
DISPLAY 0.638298 (-760 4175);
FORCEPROP 1 LAST VALUE 4.7K
J 0
(-755 4275);
DISPLAY 0.638298 (-755 4275);
FORCEPROP 1 LAST MATERIAL CHIP
J 0
(-760 4125);
DISPLAY 0.638298 (-760 4125);
FORCEPROP 2 LAST CDS_LIB pure_quanta
J 0
(-800 4200);
PAINT MONO (-800 4200);
DISPLAY INVISIBLE (-800 4200);
FORCEPROP 1 LAST PATH I23
J 0
(-750 4375);
DISPLAY 0.978723 (-750 4375);
PAINT WHITE (-750 4375);
DISPLAY INVISIBLE (-750 4375);
FORCEPROP 1 LAST PART_NUMBER CS24702JB10
J 0
(-760 4025);
DISPLAY 0.638298 (-760 4025);
DISPLAY INVISIBLE (-760 4025);
FORCEADD UNIVERSAL_POWER..1
(-800 4425);
FORCEPROP 3 LASTPIN (-800 4375) SIG_NAME P3V3_AUX\g
J 0
(-790 4385);
DISPLAY 0.659574 (-790 4385);
PAINT MONO (-790 4385);
DISPLAY INVISIBLE (-790 4385);
FORCEPROP 1 LAST HDL_POWER P3V3_AUX
J 1
(-800 4475);
DISPLAY 0.872340 (-800 4475);
PAINT GREEN (-800 4475);
FORCEPROP 2 LAST CDS_LIB pure_quanta_power
J 0
(-800 4425);
PAINT MONO (-800 4425);
DISPLAY INVISIBLE (-800 4425);
FORCEPROP 1 LAST PATH I24
J 0
(-750 4450);
DISPLAY 0.872340 (-750 4450);
PAINT AQUA (-750 4450);
DISPLAY INVISIBLE (-750 4450);
FORCEADD MOSFET_NCH_DUAL..1
(-875 4975);
FORCEPROP 1 LAST LOCATION Q135
J 0
(-724 4949);
DISPLAY 0.723404 (-724 4949);
PAINT GREEN (-724 4949);
FORCEPROP 0 LAST $SEC 1
J 0
(-700 5100);
DISPLAY 0.680851 (-700 5100);
PAINT MONO (-700 5100);
DISPLAY INVISIBLE (-700 5100);
FORCEPROP 2 LAST CDS_SEC 1
J 0
(-700 5100);
DISPLAY 1.021277 (-700 5100);
DISPLAY INVISIBLE (-700 5100);
FORCEPROP 0 LASTPIN (-825 5175) $PN 6
R 1
J 0
(-835 5185);
DISPLAY 0.680851 (-835 5185);
PAINT MONO (-835 5185);
FORCEPROP 0 LASTPIN (-1075 4925) $PN 2
J 2
(-1085 4935);
DISPLAY 0.680851 (-1085 4935);
PAINT MONO (-1085 4935);
FORCEPROP 0 LASTPIN (-825 4775) $PN 1
R 1
J 2
(-835 4765);
DISPLAY 0.680851 (-835 4765);
PAINT MONO (-835 4765);
FORCEPROP 1 LAST MATERIAL IC
J 0
(-724 4824);
DISPLAY 0.723404 (-724 4824);
PAINT GREEN (-724 4824);
FORCEPROP 2 LAST PART_TYPE SMLF
J 0
(-700 5050);
DISPLAY 1.021277 (-700 5050);
FORCEPROP 2 LAST VALUE PJT138K
J 0
(-700 5000);
DISPLAY 1.021277 (-700 5000);
FORCEPROP 2 LAST CDS_LIB pure_quanta
J 0
(-875 4975);
DISPLAY INVISIBLE (-875 4975);
FORCEPROP 1 LAST NEEDS_NO_SIZE TRUE
J 0
(-875 4974);
DISPLAY 0.468085 (-875 4974);
PAINT GREEN (-875 4974);
DISPLAY INVISIBLE (-875 4974);
FORCEPROP 1 LAST CDS_LMAN_SYM_OUTLINE -150,150,150,-150
J 0
(-875 4975);
DISPLAY 0.468085 (-875 4975);
PAINT GREEN (-875 4975);
DISPLAY INVISIBLE (-875 4975);
FORCEPROP 1 LAST PATH I25
J 0
(-875 4975);
DISPLAY 0.723404 (-875 4975);
PAINT GREEN (-875 4975);
DISPLAY INVISIBLE (-875 4975);
FORCEPROP 1 LAST PART_NUMBER BAM138K0003
J 0
(-724 4889);
DISPLAY 0.723404 (-724 4889);
PAINT GREEN (-724 4889);
DISPLAY INVISIBLE (-724 4889);
FORCEADD UNIVERSAL_GND..1
(-825 4600);
FORCEPROP 3 LASTPIN (-825 4650) SIG_NAME GND\g
J 0
(-815 4660);
DISPLAY 0.659574 (-815 4660);
PAINT MONO (-815 4660);
DISPLAY INVISIBLE (-815 4660);
FORCEPROP 2 LAST CDS_LIB pure_quanta_power
J 0
(-825 4600);
DISPLAY INVISIBLE (-825 4600);
FORCEPROP 1 LAST HDL_POWER GND
J 1
(-800 4525);
DISPLAY 0.872340 (-800 4525);
PAINT GREEN (-800 4525);
DISPLAY INVISIBLE (-800 4525);
FORCEPROP 1 LAST PATH I26
J 0
(-750 4600);
DISPLAY 0.872340 (-750 4600);
PAINT AQUA (-750 4600);
DISPLAY INVISIBLE (-750 4600);
FORCEADD Q_RES..2
(-825 5575);
FORCEPROP 1 LAST LOCATION R4164
J 0
(-780 5700);
DISPLAY 0.638298 (-780 5700);
FORCEPROP 2 LAST $SEC 1
J 0
(-775 5800);
DISPLAY 0.680851 (-775 5800);
PAINT MONO (-775 5800);
DISPLAY INVISIBLE (-775 5800);
FORCEPROP 2 LAST CDS_SEC 1
J 0
(-775 5800);
DISPLAY 1.021277 (-775 5800);
DISPLAY INVISIBLE (-775 5800);
FORCEPROP 1 LASTPIN (-825 5675) $PN 1
J 0
(-820 5637);
DISPLAY 0.787234 (-820 5637);
FORCEPROP 1 LASTPIN (-825 5475) $PN 2
J 0
(-820 5485);
DISPLAY 0.787234 (-820 5485);
FORCEPROP 1 LAST TOLERANCE 5%
J 0
(-780 5600);
DISPLAY 0.638298 (-780 5600);
FORCEPROP 1 LAST VALUE 4.7K
J 0
(-780 5650);
DISPLAY 0.638298 (-780 5650);
FORCEPROP 1 LAST WATTAGE 1/16W
J 0
(-785 5550);
DISPLAY 0.638298 (-785 5550);
FORCEPROP 1 LAST MATERIAL CHIP
J 0
(-785 5500);
DISPLAY 0.638298 (-785 5500);
FORCEPROP 1 LAST PACK_TYPE 0402LF
J 0
(-785 5450);
DISPLAY 0.638298 (-785 5450);
FORCEPROP 2 LAST CDS_LIB pure_quanta
J 0
(-825 5575);
PAINT MONO (-825 5575);
DISPLAY INVISIBLE (-825 5575);
FORCEPROP 1 LAST PATH I27
J 0
(-775 5750);
DISPLAY 0.978723 (-775 5750);
PAINT WHITE (-775 5750);
DISPLAY INVISIBLE (-775 5750);
FORCEPROP 1 LAST PART_NUMBER CS24702JB10
J 0
(-785 5400);
DISPLAY 0.638298 (-785 5400);
DISPLAY INVISIBLE (-785 5400);
FORCEADD MOSFET_NCH_DUAL..2
(300 3900);
FORCEPROP 1 LAST LOCATION Q137
J 0
(451 3876);
DISPLAY 0.723404 (451 3876);
PAINT GREEN (451 3876);
FORCEPROP 0 LAST $SEC 2
J 0
(475 4025);
DISPLAY 0.680851 (475 4025);
PAINT MONO (475 4025);
DISPLAY INVISIBLE (475 4025);
FORCEPROP 0 LAST CDS_SEC 2
J 0
(475 4025);
DISPLAY 1.021277 (475 4025);
DISPLAY INVISIBLE (475 4025);
FORCEPROP 0 LASTPIN (350 4100) $PN 3
R 1
J 0
(340 4110);
DISPLAY 0.680851 (340 4110);
PAINT MONO (340 4110);
FORCEPROP 0 LASTPIN (100 3850) $PN 5
J 2
(90 3860);
DISPLAY 0.680851 (90 3860);
PAINT MONO (90 3860);
FORCEPROP 0 LASTPIN (350 3700) $PN 4
R 1
J 2
(340 3690);
DISPLAY 0.680851 (340 3690);
PAINT MONO (340 3690);
FORCEPROP 2 LAST VALUE PJT138K
J 0
(475 3925);
DISPLAY 1.021277 (475 3925);
FORCEPROP 2 LAST PART_TYPE SMLF
J 0
(475 3975);
DISPLAY 1.021277 (475 3975);
FORCEPROP 1 LAST MATERIAL IC
J 0
(451 3751);
DISPLAY 0.723404 (451 3751);
PAINT GREEN (451 3751);
FORCEPROP 2 LAST CDS_LIB pure_quanta
J 0
(300 3900);
DISPLAY INVISIBLE (300 3900);
FORCEPROP 1 LAST NEEDS_NO_SIZE TRUE
J 0
(450 3791);
DISPLAY 0.468085 (450 3791);
PAINT GREEN (450 3791);
DISPLAY INVISIBLE (450 3791);
FORCEPROP 1 LAST CDS_LMAN_SYM_OUTLINE -150,150,150,-150
J 0
(300 3900);
DISPLAY 0.468085 (300 3900);
PAINT GREEN (300 3900);
DISPLAY INVISIBLE (300 3900);
FORCEPROP 1 LAST PATH I28
J 0
(450 3750);
DISPLAY 0.723404 (450 3750);
PAINT GREEN (450 3750);
DISPLAY INVISIBLE (450 3750);
FORCEPROP 1 LAST PART_NUMBER BAM138K0003
J 0
(451 3806);
DISPLAY 0.723404 (451 3806);
PAINT GREEN (451 3806);
DISPLAY INVISIBLE (451 3806);
FORCEADD MOSFET_NCH_DUAL..2
(275 5275);
FORCEPROP 1 LAST LOCATION Q135
J 0
(426 5251);
DISPLAY 0.723404 (426 5251);
PAINT GREEN (426 5251);
FORCEPROP 0 LAST $SEC 2
J 0
(450 5400);
DISPLAY 0.680851 (450 5400);
PAINT MONO (450 5400);
DISPLAY INVISIBLE (450 5400);
FORCEPROP 0 LAST CDS_SEC 2
J 0
(450 5400);
DISPLAY 1.021277 (450 5400);
DISPLAY INVISIBLE (450 5400);
FORCEPROP 0 LASTPIN (325 5475) $PN 3
R 1
J 0
(315 5485);
DISPLAY 0.680851 (315 5485);
PAINT MONO (315 5485);
FORCEPROP 0 LASTPIN (75 5225) $PN 5
J 2
(65 5235);
DISPLAY 0.680851 (65 5235);
PAINT MONO (65 5235);
FORCEPROP 0 LASTPIN (325 5075) $PN 4
R 1
J 2
(315 5065);
DISPLAY 0.680851 (315 5065);
PAINT MONO (315 5065);
FORCEPROP 2 LAST VALUE PJT138K
J 0
(450 5300);
DISPLAY 1.021277 (450 5300);
FORCEPROP 2 LAST PART_TYPE SMLF
J 0
(450 5350);
DISPLAY 1.021277 (450 5350);
FORCEPROP 1 LAST MATERIAL IC
J 0
(426 5126);
DISPLAY 0.723404 (426 5126);
PAINT GREEN (426 5126);
FORCEPROP 2 LAST CDS_LIB pure_quanta
J 0
(275 5275);
DISPLAY INVISIBLE (275 5275);
FORCEPROP 1 LAST NEEDS_NO_SIZE TRUE
J 0
(425 5166);
DISPLAY 0.468085 (425 5166);
PAINT GREEN (425 5166);
DISPLAY INVISIBLE (425 5166);
FORCEPROP 1 LAST CDS_LMAN_SYM_OUTLINE -150,150,150,-150
J 0
(275 5275);
DISPLAY 0.468085 (275 5275);
PAINT GREEN (275 5275);
DISPLAY INVISIBLE (275 5275);
FORCEPROP 1 LAST PATH I29
J 0
(425 5125);
DISPLAY 0.723404 (425 5125);
PAINT GREEN (425 5125);
DISPLAY INVISIBLE (425 5125);
FORCEPROP 1 LAST PART_NUMBER BAM138K0003
J 0
(426 5181);
DISPLAY 0.723404 (426 5181);
PAINT GREEN (426 5181);
DISPLAY INVISIBLE (426 5181);
FORCEADD UNIVERSAL_GND..1
(-1975 1625);
FORCEPROP 3 LASTPIN (-1975 1675) SIG_NAME GND\g
J 0
(-1965 1685);
DISPLAY 0.659574 (-1965 1685);
PAINT MONO (-1965 1685);
DISPLAY INVISIBLE (-1965 1685);
FORCEPROP 2 LAST CDS_LIB pure_quanta_power
J 0
(-1975 1625);
DISPLAY INVISIBLE (-1975 1625);
FORCEPROP 1 LAST HDL_POWER GND
J 1
(-1950 1550);
DISPLAY 0.872340 (-1950 1550);
PAINT GREEN (-1950 1550);
DISPLAY INVISIBLE (-1950 1550);
FORCEPROP 1 LAST PATH I3
J 0
(-1900 1625);
DISPLAY 0.872340 (-1900 1625);
PAINT AQUA (-1900 1625);
DISPLAY INVISIBLE (-1900 1625);
FORCEADD UNIVERSAL_POWER..1
(-825 5800);
FORCEPROP 3 LASTPIN (-825 5750) SIG_NAME P3V3_AUX\g
J 0
(-815 5760);
DISPLAY 0.659574 (-815 5760);
PAINT MONO (-815 5760);
DISPLAY INVISIBLE (-815 5760);
FORCEPROP 1 LAST HDL_POWER P3V3_AUX
J 1
(-825 5850);
DISPLAY 0.872340 (-825 5850);
PAINT GREEN (-825 5850);
FORCEPROP 2 LAST CDS_LIB pure_quanta_power
J 0
(-825 5800);
PAINT MONO (-825 5800);
DISPLAY INVISIBLE (-825 5800);
FORCEPROP 1 LAST PATH I30
J 0
(-775 5825);
DISPLAY 0.872340 (-775 5825);
PAINT AQUA (-775 5825);
DISPLAY INVISIBLE (-775 5825);
FORCEADD UNIVERSAL_GND..1
(325 4900);
FORCEPROP 3 LASTPIN (325 4950) SIG_NAME GND\g
J 0
(335 4960);
DISPLAY 0.659574 (335 4960);
PAINT MONO (335 4960);
DISPLAY INVISIBLE (335 4960);
FORCEPROP 2 LAST CDS_LIB pure_quanta_power
J 0
(325 4900);
DISPLAY INVISIBLE (325 4900);
FORCEPROP 1 LAST HDL_POWER GND
J 1
(350 4825);
DISPLAY 0.872340 (350 4825);
PAINT GREEN (350 4825);
DISPLAY INVISIBLE (350 4825);
FORCEPROP 1 LAST PATH I31
J 0
(400 4900);
DISPLAY 0.872340 (400 4900);
PAINT AQUA (400 4900);
DISPLAY INVISIBLE (400 4900);
FORCEADD UNIVERSAL_GND..1
(325 2075);
FORCEPROP 3 LASTPIN (325 2125) SIG_NAME GND\g
J 0
(335 2135);
DISPLAY 0.659574 (335 2135);
PAINT MONO (335 2135);
DISPLAY INVISIBLE (335 2135);
FORCEPROP 2 LAST CDS_LIB pure_quanta_power
J 0
(325 2075);
DISPLAY INVISIBLE (325 2075);
FORCEPROP 1 LAST HDL_POWER GND
J 1
(350 2000);
DISPLAY 0.872340 (350 2000);
PAINT GREEN (350 2000);
DISPLAY INVISIBLE (350 2000);
FORCEPROP 1 LAST PATH I32
J 0
(400 2075);
DISPLAY 0.872340 (400 2075);
PAINT AQUA (400 2075);
DISPLAY INVISIBLE (400 2075);
FORCEADD Q_CAP..1
(1100 2400);
FORCEPROP 1 LAST LOCATION C5
J 0
(1150 2500);
DISPLAY 0.978723 (1150 2500);
FORCEPROP 0 LAST $SEC 1
J 0
(1150 2550);
DISPLAY 0.680851 (1150 2550);
PAINT MONO (1150 2550);
DISPLAY INVISIBLE (1150 2550);
FORCEPROP 0 LAST CDS_SEC 1
J 0
(1150 2550);
DISPLAY 1.021277 (1150 2550);
DISPLAY INVISIBLE (1150 2550);
FORCEPROP 1 LASTPIN (1100 2500) $PN 1
J 0
(1110 2480);
DISPLAY 0.787234 (1110 2480);
PAINT MONO (1110 2480);
FORCEPROP 1 LASTPIN (1100 2300) $PN 2
J 0
(1110 2280);
DISPLAY 0.787234 (1110 2280);
PAINT MONO (1110 2280);
FORCEPROP 1 LAST TOLERANCE 10%
J 0
(1150 2350);
DISPLAY 0.638298 (1150 2350);
FORCEPROP 1 LAST VOLTAGE 25V
J 0
(1150 2400);
DISPLAY 0.638298 (1150 2400);
FORCEPROP 1 LAST MATERIAL X7R
J 0
(1150 2300);
DISPLAY 0.638298 (1150 2300);
PAINT RED (1150 2300);
FORCEPROP 1 LAST PACK_TYPE 0402
J 0
(1150 2200);
DISPLAY 0.638298 (1150 2200);
FORCEPROP 1 LAST VALUE 0.1UF
J 0
(1150 2450);
DISPLAY 0.638298 (1150 2450);
FORCEPROP 2 LAST CDS_LIB pure_quanta
J 0
(1100 2400);
DISPLAY INVISIBLE (1100 2400);
FORCEPROP 1 LAST PATH I33
J 0
(1150 2550);
DISPLAY 0.978723 (1150 2550);
PAINT WHITE (1150 2550);
DISPLAY INVISIBLE (1150 2550);
FORCEPROP 1 LAST PART_NUMBER CH4104K1B00
J 0
(1150 2250);
DISPLAY 0.638298 (1150 2250);
DISPLAY INVISIBLE (1150 2250);
FORCEADD UNIVERSAL_GND..1
(1100 2200);
FORCEPROP 3 LASTPIN (1100 2250) SIG_NAME GND\g
J 0
(1110 2260);
DISPLAY 0.659574 (1110 2260);
PAINT MONO (1110 2260);
DISPLAY INVISIBLE (1110 2260);
FORCEPROP 2 LAST CDS_LIB pure_quanta_power
J 0
(1100 2200);
DISPLAY INVISIBLE (1100 2200);
FORCEPROP 1 LAST HDL_POWER GND
J 1
(1125 2125);
DISPLAY 0.872340 (1125 2125);
PAINT GREEN (1125 2125);
DISPLAY INVISIBLE (1125 2125);
FORCEPROP 1 LAST PATH I34
J 0
(1175 2200);
DISPLAY 0.872340 (1175 2200);
PAINT AQUA (1175 2200);
DISPLAY INVISIBLE (1175 2200);
FORCEADD Q_RES..2
(325 2875);
FORCEPROP 1 LAST LOCATION R4168
J 0
(370 3000);
DISPLAY 0.638298 (370 3000);
FORCEPROP 2 LAST $SEC 1
J 0
(375 3100);
DISPLAY 0.680851 (375 3100);
PAINT MONO (375 3100);
DISPLAY INVISIBLE (375 3100);
FORCEPROP 2 LAST CDS_SEC 1
J 0
(375 3100);
DISPLAY 1.021277 (375 3100);
DISPLAY INVISIBLE (375 3100);
FORCEPROP 1 LASTPIN (325 2975) $PN 1
J 0
(330 2937);
DISPLAY 0.787234 (330 2937);
FORCEPROP 1 LASTPIN (325 2775) $PN 2
J 0
(330 2785);
DISPLAY 0.787234 (330 2785);
FORCEPROP 1 LAST TOLERANCE 1%
J 0
(370 2900);
DISPLAY 0.638298 (370 2900);
FORCEPROP 1 LAST VALUE 100K
J 0
(370 2950);
DISPLAY 0.638298 (370 2950);
FORCEPROP 1 LAST MATERIAL CHIP
J 0
(365 2800);
DISPLAY 0.638298 (365 2800);
FORCEPROP 1 LAST WATTAGE 1/16W
J 0
(365 2850);
DISPLAY 0.638298 (365 2850);
FORCEPROP 1 LAST PACK_TYPE 0402LF
J 0
(365 2750);
DISPLAY 0.638298 (365 2750);
FORCEPROP 2 LAST CDS_LIB pure_quanta
J 0
(325 2875);
PAINT MONO (325 2875);
DISPLAY INVISIBLE (325 2875);
FORCEPROP 1 LAST PATH I35
J 0
(375 3050);
DISPLAY 0.978723 (375 3050);
PAINT WHITE (375 3050);
DISPLAY INVISIBLE (375 3050);
FORCEPROP 1 LAST PART_NUMBER CS41002FB09
J 0
(365 2700);
DISPLAY 0.638298 (365 2700);
DISPLAY INVISIBLE (365 2700);
FORCEADD UNIVERSAL_POWER..1
(325 3100);
FORCEPROP 3 LASTPIN (325 3050) SIG_NAME P3V3_AUX\g
J 0
(335 3060);
DISPLAY 0.659574 (335 3060);
PAINT MONO (335 3060);
DISPLAY INVISIBLE (335 3060);
FORCEPROP 1 LAST HDL_POWER P3V3_AUX
J 1
(325 3150);
DISPLAY 0.872340 (325 3150);
PAINT GREEN (325 3150);
FORCEPROP 2 LAST CDS_LIB pure_quanta_power
J 0
(325 3100);
PAINT MONO (325 3100);
DISPLAY INVISIBLE (325 3100);
FORCEPROP 1 LAST PATH I36
J 0
(375 3125);
DISPLAY 0.872340 (375 3125);
PAINT AQUA (375 3125);
DISPLAY INVISIBLE (375 3125);
FORCEADD UNIVERSAL_GND..1
(350 3525);
FORCEPROP 3 LASTPIN (350 3575) SIG_NAME GND\g
J 0
(360 3585);
DISPLAY 0.659574 (360 3585);
PAINT MONO (360 3585);
DISPLAY INVISIBLE (360 3585);
FORCEPROP 2 LAST CDS_LIB pure_quanta_power
J 0
(350 3525);
DISPLAY INVISIBLE (350 3525);
FORCEPROP 1 LAST HDL_POWER GND
J 1
(375 3450);
DISPLAY 0.872340 (375 3450);
PAINT GREEN (375 3450);
DISPLAY INVISIBLE (375 3450);
FORCEPROP 1 LAST PATH I37
J 0
(425 3525);
DISPLAY 0.872340 (425 3525);
PAINT AQUA (425 3525);
DISPLAY INVISIBLE (425 3525);
FORCEADD OFFPAGE..2
(1450 2700);
FORCEPROP 2 LAST $XR0 81 
J 0
(1639 2700);
DISPLAY 0.638298 (1639 2700);
PAINT MONO (1639 2700);
FORCEPROP 2 LAST CDS_LIB standard
J 0
(1450 2700);
DISPLAY INVISIBLE (1450 2700);
FORCEPROP 1 LAST OFFPAGE TRUE
J 0
(1775 2575);
DISPLAY 0.872340 (1775 2575);
PAINT AQUA (1775 2575);
DISPLAY INVISIBLE (1775 2575);
FORCEPROP 1 LAST COMMENT_BODY TRUE
J 0
(1405 2605);
DISPLAY 0.872340 (1405 2605);
PAINT GREEN (1405 2605);
DISPLAY INVISIBLE (1405 2605);
FORCEPROP 2 LAST PATH I38
J 0
(1650 2750);
DISPLAY 1.021277 (1650 2750);
DISPLAY INVISIBLE (1650 2750);
FORCEADD Q_RES..2
(350 4325);
FORCEPROP 1 LAST LOCATION R4169
J 0
(395 4450);
DISPLAY 0.638298 (395 4450);
FORCEPROP 2 LAST $SEC 1
J 0
(400 4550);
DISPLAY 0.680851 (400 4550);
PAINT MONO (400 4550);
DISPLAY INVISIBLE (400 4550);
FORCEPROP 2 LAST CDS_SEC 1
J 0
(400 4550);
DISPLAY 1.021277 (400 4550);
DISPLAY INVISIBLE (400 4550);
FORCEPROP 1 LASTPIN (350 4425) $PN 1
J 0
(355 4387);
DISPLAY 0.787234 (355 4387);
FORCEPROP 1 LASTPIN (350 4225) $PN 2
J 0
(355 4235);
DISPLAY 0.787234 (355 4235);
FORCEPROP 1 LAST TOLERANCE 1%
J 0
(395 4350);
DISPLAY 0.638298 (395 4350);
FORCEPROP 1 LAST VALUE 100K
J 0
(395 4400);
DISPLAY 0.638298 (395 4400);
FORCEPROP 1 LAST PACK_TYPE 0402LF
J 0
(390 4200);
DISPLAY 0.638298 (390 4200);
FORCEPROP 1 LAST WATTAGE 1/16W
J 0
(390 4300);
DISPLAY 0.638298 (390 4300);
FORCEPROP 1 LAST MATERIAL CHIP
J 0
(390 4250);
DISPLAY 0.638298 (390 4250);
FORCEPROP 2 LAST CDS_LIB pure_quanta
J 0
(350 4325);
PAINT MONO (350 4325);
DISPLAY INVISIBLE (350 4325);
FORCEPROP 1 LAST PATH I39
J 0
(400 4500);
DISPLAY 0.978723 (400 4500);
PAINT WHITE (400 4500);
DISPLAY INVISIBLE (400 4500);
FORCEPROP 1 LAST PART_NUMBER CS41002FB09
J 0
(390 4150);
DISPLAY 0.638298 (390 4150);
DISPLAY INVISIBLE (390 4150);
FORCEADD Q_RES..2
(-2000 2375);
FORCEPROP 1 LAST LOCATION R4160
J 0
(-1955 2500);
DISPLAY 0.978723 (-1955 2500);
FORCEPROP 0 LAST $SEC 1
J 0
(-1950 2550);
DISPLAY 0.680851 (-1950 2550);
PAINT MONO (-1950 2550);
DISPLAY INVISIBLE (-1950 2550);
FORCEPROP 0 LAST CDS_SEC 1
J 0
(-1950 2550);
DISPLAY 1.021277 (-1950 2550);
DISPLAY INVISIBLE (-1950 2550);
FORCEPROP 1 LASTPIN (-2000 2475) $PN 1
J 0
(-1995 2437);
DISPLAY 0.787234 (-1995 2437);
PAINT MONO (-1995 2437);
FORCEPROP 1 LASTPIN (-2000 2275) $PN 2
J 0
(-1995 2285);
DISPLAY 0.787234 (-1995 2285);
PAINT MONO (-1995 2285);
FORCEPROP 1 LAST VALUE 54.9K
J 0
(-1955 2450);
DISPLAY 0.787234 (-1955 2450);
FORCEPROP 1 LAST TOLERANCE 1%
J 0
(-1955 2400);
DISPLAY 0.787234 (-1955 2400);
FORCEPROP 1 LAST WATTAGE 1/16W
J 0
(-1960 2350);
DISPLAY 0.787234 (-1960 2350);
FORCEPROP 1 LAST MATERIAL EMPTY
J 0
(-1960 2300);
DISPLAY 0.787234 (-1960 2300);
PAINT RED (-1960 2300);
FORCEPROP 1 LAST PACK_TYPE 0402LF
J 0
(-1960 2200);
DISPLAY 0.787234 (-1960 2200);
FORCEPROP 2 LAST CDS_LIB pure_quanta
J 0
(-2000 2375);
DISPLAY INVISIBLE (-2000 2375);
FORCEPROP 1 LAST PATH I4
J 0
(-1950 2550);
DISPLAY 0.978723 (-1950 2550);
PAINT WHITE (-1950 2550);
DISPLAY INVISIBLE (-1950 2550);
FORCEPROP 1 LAST PART_NUMBER CS35492FB03
J 0
(-1960 2250);
DISPLAY 0.787234 (-1960 2250);
DISPLAY INVISIBLE (-1960 2250);
FORCEADD UNIVERSAL_POWER..1
(350 4550);
FORCEPROP 3 LASTPIN (350 4500) SIG_NAME P3V3_AUX\g
J 0
(360 4510);
DISPLAY 0.659574 (360 4510);
PAINT MONO (360 4510);
DISPLAY INVISIBLE (360 4510);
FORCEPROP 1 LAST HDL_POWER P3V3_AUX
J 1
(350 4600);
DISPLAY 0.872340 (350 4600);
PAINT GREEN (350 4600);
FORCEPROP 2 LAST CDS_LIB pure_quanta_power
J 0
(350 4550);
PAINT MONO (350 4550);
DISPLAY INVISIBLE (350 4550);
FORCEPROP 1 LAST PATH I40
J 0
(400 4575);
DISPLAY 0.872340 (400 4575);
PAINT AQUA (400 4575);
DISPLAY INVISIBLE (400 4575);
FORCEADD UNIVERSAL_GND..1
(1125 3650);
FORCEPROP 3 LASTPIN (1125 3700) SIG_NAME GND\g
J 0
(1135 3710);
DISPLAY 0.659574 (1135 3710);
PAINT MONO (1135 3710);
DISPLAY INVISIBLE (1135 3710);
FORCEPROP 2 LAST CDS_LIB pure_quanta_power
J 0
(1125 3650);
DISPLAY INVISIBLE (1125 3650);
FORCEPROP 1 LAST HDL_POWER GND
J 1
(1150 3575);
DISPLAY 0.872340 (1150 3575);
PAINT GREEN (1150 3575);
DISPLAY INVISIBLE (1150 3575);
FORCEPROP 1 LAST PATH I41
J 0
(1200 3650);
DISPLAY 0.872340 (1200 3650);
PAINT AQUA (1200 3650);
DISPLAY INVISIBLE (1200 3650);
FORCEADD Q_CAP..1
(1125 3850);
FORCEPROP 1 LAST LOCATION C7
J 0
(1175 3950);
DISPLAY 0.978723 (1175 3950);
FORCEPROP 0 LAST $SEC 1
J 0
(1175 4000);
DISPLAY 0.680851 (1175 4000);
PAINT MONO (1175 4000);
DISPLAY INVISIBLE (1175 4000);
FORCEPROP 0 LAST CDS_SEC 1
J 0
(1175 4000);
DISPLAY 1.021277 (1175 4000);
DISPLAY INVISIBLE (1175 4000);
FORCEPROP 1 LASTPIN (1125 3950) $PN 1
J 0
(1135 3930);
DISPLAY 0.787234 (1135 3930);
PAINT MONO (1135 3930);
FORCEPROP 1 LASTPIN (1125 3750) $PN 2
J 0
(1135 3730);
DISPLAY 0.787234 (1135 3730);
PAINT MONO (1135 3730);
FORCEPROP 1 LAST PACK_TYPE 0402
J 0
(1175 3650);
DISPLAY 0.638298 (1175 3650);
FORCEPROP 1 LAST MATERIAL X7R
J 0
(1175 3750);
DISPLAY 0.638298 (1175 3750);
PAINT RED (1175 3750);
FORCEPROP 1 LAST TOLERANCE 10%
J 0
(1175 3800);
DISPLAY 0.638298 (1175 3800);
FORCEPROP 1 LAST VOLTAGE 25V
J 0
(1175 3850);
DISPLAY 0.638298 (1175 3850);
FORCEPROP 1 LAST VALUE 0.1UF
J 0
(1175 3900);
DISPLAY 0.638298 (1175 3900);
FORCEPROP 2 LAST CDS_LIB pure_quanta
J 0
(1125 3850);
DISPLAY INVISIBLE (1125 3850);
FORCEPROP 1 LAST PATH I42
J 0
(1175 4000);
DISPLAY 0.978723 (1175 4000);
PAINT WHITE (1175 4000);
DISPLAY INVISIBLE (1175 4000);
FORCEPROP 1 LAST PART_NUMBER CH4104K1B00
J 0
(1175 3700);
DISPLAY 0.638298 (1175 3700);
DISPLAY INVISIBLE (1175 3700);
FORCEADD UNIVERSAL_GND..1
(1100 5025);
FORCEPROP 3 LASTPIN (1100 5075) SIG_NAME GND\g
J 0
(1110 5085);
DISPLAY 0.659574 (1110 5085);
PAINT MONO (1110 5085);
DISPLAY INVISIBLE (1110 5085);
FORCEPROP 2 LAST CDS_LIB pure_quanta_power
J 0
(1100 5025);
DISPLAY INVISIBLE (1100 5025);
FORCEPROP 1 LAST HDL_POWER GND
J 1
(1125 4950);
DISPLAY 0.872340 (1125 4950);
PAINT GREEN (1125 4950);
DISPLAY INVISIBLE (1125 4950);
FORCEPROP 1 LAST PATH I43
J 0
(1175 5025);
DISPLAY 0.872340 (1175 5025);
PAINT AQUA (1175 5025);
DISPLAY INVISIBLE (1175 5025);
FORCEADD Q_CAP..1
(1100 5225);
FORCEPROP 1 LAST LOCATION C4
J 0
(1150 5325);
DISPLAY 0.978723 (1150 5325);
FORCEPROP 0 LAST $SEC 1
J 0
(1150 5375);
DISPLAY 0.680851 (1150 5375);
PAINT MONO (1150 5375);
DISPLAY INVISIBLE (1150 5375);
FORCEPROP 0 LAST CDS_SEC 1
J 0
(1150 5375);
DISPLAY 1.021277 (1150 5375);
DISPLAY INVISIBLE (1150 5375);
FORCEPROP 1 LASTPIN (1100 5325) $PN 1
J 0
(1110 5305);
DISPLAY 0.787234 (1110 5305);
PAINT MONO (1110 5305);
FORCEPROP 1 LASTPIN (1100 5125) $PN 2
J 0
(1110 5105);
DISPLAY 0.787234 (1110 5105);
PAINT MONO (1110 5105);
FORCEPROP 1 LAST PACK_TYPE 0402
J 0
(1150 5025);
DISPLAY 0.638298 (1150 5025);
FORCEPROP 1 LAST MATERIAL X7R
J 0
(1150 5125);
DISPLAY 0.638298 (1150 5125);
PAINT RED (1150 5125);
FORCEPROP 1 LAST TOLERANCE 10%
J 0
(1150 5175);
DISPLAY 0.638298 (1150 5175);
FORCEPROP 1 LAST VOLTAGE 25V
J 0
(1150 5225);
DISPLAY 0.638298 (1150 5225);
FORCEPROP 1 LAST VALUE 0.1UF
J 0
(1150 5275);
DISPLAY 0.638298 (1150 5275);
FORCEPROP 2 LAST CDS_LIB pure_quanta
J 0
(1100 5225);
DISPLAY INVISIBLE (1100 5225);
FORCEPROP 1 LAST PATH I44
J 0
(1150 5375);
DISPLAY 0.978723 (1150 5375);
PAINT WHITE (1150 5375);
DISPLAY INVISIBLE (1150 5375);
FORCEPROP 1 LAST PART_NUMBER CH4104K1B00
J 0
(1150 5075);
DISPLAY 0.638298 (1150 5075);
DISPLAY INVISIBLE (1150 5075);
FORCEADD OFFPAGE..2
(1475 4150);
FORCEPROP 2 LAST $XR0 81 
J 0
(1664 4150);
DISPLAY 0.638298 (1664 4150);
PAINT MONO (1664 4150);
FORCEPROP 2 LAST CDS_LIB standard
J 0
(1475 4150);
DISPLAY INVISIBLE (1475 4150);
FORCEPROP 1 LAST OFFPAGE TRUE
J 0
(1800 4025);
DISPLAY 0.872340 (1800 4025);
PAINT AQUA (1800 4025);
DISPLAY INVISIBLE (1800 4025);
FORCEPROP 1 LAST COMMENT_BODY TRUE
J 0
(1430 4055);
DISPLAY 0.872340 (1430 4055);
PAINT GREEN (1430 4055);
DISPLAY INVISIBLE (1430 4055);
FORCEPROP 2 LAST PATH I45
J 0
(1675 4200);
DISPLAY 1.021277 (1675 4200);
DISPLAY INVISIBLE (1675 4200);
FORCEADD OFFPAGE..2
(1450 5525);
FORCEPROP 2 LAST $XR0 81 
J 0
(1639 5525);
DISPLAY 0.638298 (1639 5525);
PAINT MONO (1639 5525);
FORCEPROP 2 LAST CDS_LIB standard
J 0
(1450 5525);
DISPLAY INVISIBLE (1450 5525);
FORCEPROP 1 LAST OFFPAGE TRUE
J 0
(1775 5400);
DISPLAY 0.872340 (1775 5400);
PAINT AQUA (1775 5400);
DISPLAY INVISIBLE (1775 5400);
FORCEPROP 1 LAST COMMENT_BODY TRUE
J 0
(1405 5430);
DISPLAY 0.872340 (1405 5430);
PAINT GREEN (1405 5430);
DISPLAY INVISIBLE (1405 5430);
FORCEPROP 2 LAST PATH I46
J 0
(1650 5575);
DISPLAY 1.021277 (1650 5575);
DISPLAY INVISIBLE (1650 5575);
FORCEADD Q_RES..2
(325 5700);
FORCEPROP 1 LAST LOCATION R4167
J 0
(370 5825);
DISPLAY 0.638298 (370 5825);
FORCEPROP 2 LAST $SEC 1
J 0
(375 5925);
DISPLAY 0.680851 (375 5925);
PAINT MONO (375 5925);
DISPLAY INVISIBLE (375 5925);
FORCEPROP 2 LAST CDS_SEC 1
J 0
(375 5925);
DISPLAY 1.021277 (375 5925);
DISPLAY INVISIBLE (375 5925);
FORCEPROP 1 LASTPIN (325 5800) $PN 1
J 0
(330 5762);
DISPLAY 0.787234 (330 5762);
FORCEPROP 1 LASTPIN (325 5600) $PN 2
J 0
(330 5610);
DISPLAY 0.787234 (330 5610);
FORCEPROP 1 LAST TOLERANCE 1%
J 0
(370 5725);
DISPLAY 0.638298 (370 5725);
FORCEPROP 1 LAST VALUE 100K
J 0
(370 5775);
DISPLAY 0.638298 (370 5775);
FORCEPROP 1 LAST MATERIAL CHIP
J 0
(365 5625);
DISPLAY 0.638298 (365 5625);
FORCEPROP 1 LAST PACK_TYPE 0402LF
J 0
(365 5575);
DISPLAY 0.638298 (365 5575);
FORCEPROP 1 LAST WATTAGE 1/16W
J 0
(365 5675);
DISPLAY 0.638298 (365 5675);
FORCEPROP 2 LAST CDS_LIB pure_quanta
J 0
(325 5700);
PAINT MONO (325 5700);
DISPLAY INVISIBLE (325 5700);
FORCEPROP 1 LAST PATH I47
J 0
(375 5875);
DISPLAY 0.978723 (375 5875);
PAINT WHITE (375 5875);
DISPLAY INVISIBLE (375 5875);
FORCEPROP 1 LAST PART_NUMBER CS41002FB09
J 0
(365 5525);
DISPLAY 0.638298 (365 5525);
DISPLAY INVISIBLE (365 5525);
FORCEADD UNIVERSAL_POWER..1
(325 5925);
FORCEPROP 3 LASTPIN (325 5875) SIG_NAME P3V3_AUX\g
J 0
(335 5885);
DISPLAY 0.659574 (335 5885);
PAINT MONO (335 5885);
DISPLAY INVISIBLE (335 5885);
FORCEPROP 1 LAST HDL_POWER P3V3_AUX
J 1
(325 5975);
DISPLAY 0.872340 (325 5975);
PAINT GREEN (325 5975);
FORCEPROP 2 LAST CDS_LIB pure_quanta_power
J 0
(325 5925);
PAINT MONO (325 5925);
DISPLAY INVISIBLE (325 5925);
FORCEPROP 1 LAST PATH I48
J 0
(375 5950);
DISPLAY 0.872340 (375 5950);
PAINT AQUA (375 5950);
DISPLAY INVISIBLE (375 5950);
FORCEADD UNIVERSAL_POWER..1
(325 1475);
FORCEPROP 3 LASTPIN (325 1425) SIG_NAME P3V3_AUX\g
J 0
(335 1435);
DISPLAY 0.659574 (335 1435);
PAINT MONO (335 1435);
DISPLAY INVISIBLE (335 1435);
FORCEPROP 1 LAST HDL_POWER P3V3_AUX
J 1
(325 1525);
DISPLAY 0.872340 (325 1525);
PAINT GREEN (325 1525);
FORCEPROP 2 LAST CDS_LIB pure_quanta_power
J 0
(325 1475);
PAINT MONO (325 1475);
DISPLAY INVISIBLE (325 1475);
FORCEPROP 1 LAST PATH I49
J 0
(375 1500);
DISPLAY 0.872340 (375 1500);
PAINT AQUA (375 1500);
DISPLAY INVISIBLE (375 1500);
FORCEADD OFFPAGE..4
R 2
(-2225 3550);
FORCEPROP 2 LAST $XR0 115 
J 0
(-2477 3550);
DISPLAY 0.638298 (-2477 3550);
PAINT MONO (-2477 3550);
FORCEPROP 2 LAST CDS_LIB standard
J 0
(-2225 3550);
DISPLAY INVISIBLE (-2225 3550);
FORCEPROP 1 LAST OFFPAGE TRUE
J 2
(-2550 3425);
DISPLAY 0.872340 (-2550 3425);
PAINT GREEN (-2550 3425);
DISPLAY INVISIBLE (-2550 3425);
FORCEPROP 1 LAST COMMENT_BODY TRUE
J 2
(-2200 3450);
DISPLAY 0.872340 (-2200 3450);
PAINT GREEN (-2200 3450);
DISPLAY INVISIBLE (-2200 3450);
FORCEPROP 2 LAST PATH I5
J 0
(-2475 3600);
DISPLAY 1.021277 (-2475 3600);
DISPLAY INVISIBLE (-2475 3600);
FORCEADD OFFPAGE..2
(1450 1075);
FORCEPROP 2 LAST $XR1 122 
J 0
(1759 1075);
DISPLAY 0.638298 (1759 1075);
PAINT MONO (1759 1075);
FORCEPROP 2 LAST $XR0 123 
J 0
(1639 1075);
DISPLAY 0.638298 (1639 1075);
PAINT MONO (1639 1075);
FORCEPROP 2 LAST CDS_LIB standard
J 0
(1450 1075);
DISPLAY INVISIBLE (1450 1075);
FORCEPROP 1 LAST OFFPAGE TRUE
J 0
(1775 950);
DISPLAY 0.872340 (1775 950);
PAINT AQUA (1775 950);
DISPLAY INVISIBLE (1775 950);
FORCEPROP 1 LAST COMMENT_BODY TRUE
J 0
(1405 980);
DISPLAY 0.872340 (1405 980);
PAINT GREEN (1405 980);
DISPLAY INVISIBLE (1405 980);
FORCEPROP 2 LAST PATH I51
J 0
(1650 1125);
DISPLAY 1.021277 (1650 1125);
DISPLAY INVISIBLE (1650 1125);
FORCEADD UNIVERSAL_GND..1
(1100 575);
FORCEPROP 3 LASTPIN (1100 625) SIG_NAME GND\g
J 0
(1110 635);
DISPLAY 0.659574 (1110 635);
PAINT MONO (1110 635);
DISPLAY INVISIBLE (1110 635);
FORCEPROP 2 LAST CDS_LIB pure_quanta_power
J 0
(1100 575);
DISPLAY INVISIBLE (1100 575);
FORCEPROP 1 LAST HDL_POWER GND
J 1
(1125 500);
DISPLAY 0.872340 (1125 500);
PAINT GREEN (1125 500);
DISPLAY INVISIBLE (1125 500);
FORCEPROP 1 LAST PATH I53
J 0
(1175 575);
DISPLAY 0.872340 (1175 575);
PAINT AQUA (1175 575);
DISPLAY INVISIBLE (1175 575);
FORCEADD UNIVERSAL_GND..1
(325 450);
FORCEPROP 3 LASTPIN (325 500) SIG_NAME GND\g
J 0
(335 510);
DISPLAY 0.659574 (335 510);
PAINT MONO (335 510);
DISPLAY INVISIBLE (335 510);
FORCEPROP 2 LAST CDS_LIB pure_quanta_power
J 0
(325 450);
DISPLAY INVISIBLE (325 450);
FORCEPROP 1 LAST HDL_POWER GND
J 1
(350 375);
DISPLAY 0.872340 (350 375);
PAINT GREEN (350 375);
DISPLAY INVISIBLE (350 375);
FORCEPROP 1 LAST PATH I54
J 0
(400 450);
DISPLAY 0.872340 (400 450);
PAINT AQUA (400 450);
DISPLAY INVISIBLE (400 450);
FORCEADD MOSFET_NCH_DUAL..2
(275 825);
FORCEPROP 1 LAST LOCATION Q148
J 0
(426 801);
DISPLAY 0.723404 (426 801);
PAINT GREEN (426 801);
FORCEPROP 0 LAST $SEC 2
J 0
(450 950);
DISPLAY 0.680851 (450 950);
PAINT MONO (450 950);
DISPLAY INVISIBLE (450 950);
FORCEPROP 0 LAST CDS_SEC 2
J 0
(450 950);
DISPLAY 1.021277 (450 950);
DISPLAY INVISIBLE (450 950);
FORCEPROP 0 LASTPIN (325 1025) $PN 3
R 1
J 0
(315 1035);
DISPLAY 0.680851 (315 1035);
PAINT MONO (315 1035);
FORCEPROP 0 LASTPIN (75 775) $PN 5
J 2
(65 785);
DISPLAY 0.680851 (65 785);
PAINT MONO (65 785);
FORCEPROP 0 LASTPIN (325 625) $PN 4
R 1
J 2
(315 615);
DISPLAY 0.680851 (315 615);
PAINT MONO (315 615);
FORCEPROP 1 LAST MATERIAL IC
J 0
(426 676);
DISPLAY 0.723404 (426 676);
PAINT GREEN (426 676);
FORCEPROP 2 LAST PART_TYPE SMLF
J 0
(450 900);
DISPLAY 1.021277 (450 900);
FORCEPROP 2 LAST VALUE PJT138K
J 0
(450 850);
DISPLAY 1.021277 (450 850);
FORCEPROP 2 LAST CDS_LIB pure_quanta
J 0
(275 825);
DISPLAY INVISIBLE (275 825);
FORCEPROP 1 LAST NEEDS_NO_SIZE TRUE
J 0
(425 716);
DISPLAY 0.468085 (425 716);
PAINT GREEN (425 716);
DISPLAY INVISIBLE (425 716);
FORCEPROP 1 LAST CDS_LMAN_SYM_OUTLINE -150,150,150,-150
J 0
(275 825);
DISPLAY 0.468085 (275 825);
PAINT GREEN (275 825);
DISPLAY INVISIBLE (275 825);
FORCEPROP 1 LAST PATH I55
J 0
(425 675);
DISPLAY 0.723404 (425 675);
PAINT GREEN (425 675);
DISPLAY INVISIBLE (425 675);
FORCEPROP 1 LAST PART_NUMBER BAM138K0003
J 0
(426 731);
DISPLAY 0.723404 (426 731);
PAINT GREEN (426 731);
DISPLAY INVISIBLE (426 731);
FORCEADD UNIVERSAL_POWER..1
(-825 1350);
FORCEPROP 3 LASTPIN (-825 1300) SIG_NAME P3V3_AUX\g
J 0
(-815 1310);
DISPLAY 0.659574 (-815 1310);
PAINT MONO (-815 1310);
DISPLAY INVISIBLE (-815 1310);
FORCEPROP 1 LAST HDL_POWER P3V3_AUX
J 1
(-825 1400);
DISPLAY 0.872340 (-825 1400);
PAINT GREEN (-825 1400);
FORCEPROP 2 LAST CDS_LIB pure_quanta_power
J 0
(-825 1350);
PAINT MONO (-825 1350);
DISPLAY INVISIBLE (-825 1350);
FORCEPROP 1 LAST PATH I56
J 0
(-775 1375);
DISPLAY 0.872340 (-775 1375);
PAINT AQUA (-775 1375);
DISPLAY INVISIBLE (-775 1375);
FORCEADD Q_RES..2
(-825 1125);
FORCEPROP 1 LAST LOCATION R4545
J 0
(-780 1250);
DISPLAY 0.638298 (-780 1250);
FORCEPROP 2 LAST $SEC 1
J 0
(-775 1350);
DISPLAY 0.680851 (-775 1350);
PAINT MONO (-775 1350);
DISPLAY INVISIBLE (-775 1350);
FORCEPROP 2 LAST CDS_SEC 1
J 0
(-775 1350);
DISPLAY 1.021277 (-775 1350);
DISPLAY INVISIBLE (-775 1350);
FORCEPROP 1 LASTPIN (-825 1225) $PN 1
J 0
(-820 1187);
DISPLAY 0.787234 (-820 1187);
FORCEPROP 1 LASTPIN (-825 1025) $PN 2
J 0
(-820 1035);
DISPLAY 0.787234 (-820 1035);
FORCEPROP 1 LAST WATTAGE 1/16W
J 0
(-785 1100);
DISPLAY 0.638298 (-785 1100);
FORCEPROP 1 LAST TOLERANCE 5%
J 0
(-780 1150);
DISPLAY 0.638298 (-780 1150);
FORCEPROP 1 LAST VALUE 4.7K
J 0
(-780 1200);
DISPLAY 0.638298 (-780 1200);
FORCEPROP 1 LAST MATERIAL CHIP
J 0
(-785 1050);
DISPLAY 0.638298 (-785 1050);
FORCEPROP 1 LAST PACK_TYPE 0402LF
J 0
(-785 1000);
DISPLAY 0.638298 (-785 1000);
FORCEPROP 2 LAST CDS_LIB pure_quanta
J 0
(-825 1125);
PAINT MONO (-825 1125);
DISPLAY INVISIBLE (-825 1125);
FORCEPROP 1 LAST PATH I57
J 0
(-775 1300);
DISPLAY 0.978723 (-775 1300);
PAINT WHITE (-775 1300);
DISPLAY INVISIBLE (-775 1300);
FORCEPROP 1 LAST PART_NUMBER CS24702JB10
J 0
(-785 950);
DISPLAY 0.638298 (-785 950);
DISPLAY INVISIBLE (-785 950);
FORCEADD UNIVERSAL_POWER..1
(-2000 1000);
FORCEPROP 3 LASTPIN (-2000 950) SIG_NAME P3V3_AUX\g
J 0
(-1990 960);
DISPLAY 0.659574 (-1990 960);
PAINT MONO (-1990 960);
DISPLAY INVISIBLE (-1990 960);
FORCEPROP 1 LAST HDL_POWER P3V3_AUX
J 1
(-2000 1050);
DISPLAY 0.872340 (-2000 1050);
PAINT GREEN (-2000 1050);
FORCEPROP 2 LAST CDS_LIB pure_quanta_power
J 0
(-2000 1000);
PAINT MONO (-2000 1000);
DISPLAY INVISIBLE (-2000 1000);
FORCEPROP 1 LAST PATH I58
J 0
(-1950 1025);
DISPLAY 0.872340 (-1950 1025);
PAINT AQUA (-1950 1025);
DISPLAY INVISIBLE (-1950 1025);
FORCEADD UNIVERSAL_POWER..1
(-2000 2625);
FORCEPROP 3 LASTPIN (-2000 2575) SIG_NAME P3V3_AUX\g
J 0
(-1990 2585);
DISPLAY 0.659574 (-1990 2585);
PAINT MONO (-1990 2585);
DISPLAY INVISIBLE (-1990 2585);
FORCEPROP 1 LAST HDL_POWER P3V3_AUX
J 1
(-2000 2675);
DISPLAY 0.872340 (-2000 2675);
PAINT GREEN (-2000 2675);
FORCEPROP 2 LAST CDS_LIB pure_quanta_power
J 0
(-2000 2625);
PAINT MONO (-2000 2625);
DISPLAY INVISIBLE (-2000 2625);
FORCEPROP 1 LAST PATH I6
J 0
(-1950 2650);
DISPLAY 0.872340 (-1950 2650);
PAINT AQUA (-1950 2650);
DISPLAY INVISIBLE (-1950 2650);
FORCEADD UNIVERSAL_GND..1
(-825 150);
FORCEPROP 3 LASTPIN (-825 200) SIG_NAME GND\g
J 0
(-815 210);
DISPLAY 0.659574 (-815 210);
PAINT MONO (-815 210);
DISPLAY INVISIBLE (-815 210);
FORCEPROP 2 LAST CDS_LIB pure_quanta_power
J 0
(-825 150);
DISPLAY INVISIBLE (-825 150);
FORCEPROP 1 LAST HDL_POWER GND
J 1
(-800 75);
DISPLAY 0.872340 (-800 75);
PAINT GREEN (-800 75);
DISPLAY INVISIBLE (-800 75);
FORCEPROP 1 LAST PATH I60
J 0
(-750 150);
DISPLAY 0.872340 (-750 150);
PAINT AQUA (-750 150);
DISPLAY INVISIBLE (-750 150);
FORCEADD MOSFET_NCH_DUAL..1
(-875 525);
FORCEPROP 1 LAST LOCATION Q148
J 0
(-724 499);
DISPLAY 0.723404 (-724 499);
PAINT GREEN (-724 499);
FORCEPROP 0 LAST $SEC 1
J 0
(-700 650);
DISPLAY 0.680851 (-700 650);
PAINT MONO (-700 650);
DISPLAY INVISIBLE (-700 650);
FORCEPROP 2 LAST CDS_SEC 1
J 0
(-700 650);
DISPLAY 1.021277 (-700 650);
DISPLAY INVISIBLE (-700 650);
FORCEPROP 0 LASTPIN (-825 725) $PN 6
R 1
J 0
(-835 735);
DISPLAY 0.680851 (-835 735);
PAINT MONO (-835 735);
FORCEPROP 0 LASTPIN (-1075 475) $PN 2
J 2
(-1085 485);
DISPLAY 0.680851 (-1085 485);
PAINT MONO (-1085 485);
FORCEPROP 0 LASTPIN (-825 325) $PN 1
R 1
J 2
(-835 315);
DISPLAY 0.680851 (-835 315);
PAINT MONO (-835 315);
FORCEPROP 2 LAST PART_TYPE SMLF
J 0
(-700 600);
DISPLAY 1.021277 (-700 600);
FORCEPROP 1 LAST MATERIAL IC
J 0
(-724 374);
DISPLAY 0.723404 (-724 374);
PAINT GREEN (-724 374);
FORCEPROP 2 LAST VALUE PJT138K
J 0
(-700 550);
DISPLAY 1.021277 (-700 550);
FORCEPROP 2 LAST CDS_LIB pure_quanta
J 0
(-875 525);
DISPLAY INVISIBLE (-875 525);
FORCEPROP 1 LAST NEEDS_NO_SIZE TRUE
J 0
(-875 524);
DISPLAY 0.468085 (-875 524);
PAINT GREEN (-875 524);
DISPLAY INVISIBLE (-875 524);
FORCEPROP 1 LAST CDS_LMAN_SYM_OUTLINE -150,150,150,-150
J 0
(-875 525);
DISPLAY 0.468085 (-875 525);
PAINT GREEN (-875 525);
DISPLAY INVISIBLE (-875 525);
FORCEPROP 1 LAST PATH I61
J 0
(-875 525);
DISPLAY 0.723404 (-875 525);
PAINT GREEN (-875 525);
DISPLAY INVISIBLE (-875 525);
FORCEPROP 1 LAST PART_NUMBER BAM138K0003
J 0
(-724 439);
DISPLAY 0.723404 (-724 439);
PAINT GREEN (-724 439);
DISPLAY INVISIBLE (-724 439);
FORCEADD Q_RES..2
(-1975 275);
FORCEPROP 1 LAST LOCATION R4544
J 0
(-1930 400);
DISPLAY 0.978723 (-1930 400);
FORCEPROP 0 LAST $SEC 1
J 0
(-1925 450);
DISPLAY 0.680851 (-1925 450);
PAINT MONO (-1925 450);
DISPLAY INVISIBLE (-1925 450);
FORCEPROP 0 LAST CDS_SEC 1
J 0
(-1925 450);
DISPLAY 1.021277 (-1925 450);
DISPLAY INVISIBLE (-1925 450);
FORCEPROP 1 LASTPIN (-1975 375) $PN 1
J 0
(-1970 337);
DISPLAY 0.787234 (-1970 337);
PAINT MONO (-1970 337);
FORCEPROP 1 LASTPIN (-1975 175) $PN 2
J 0
(-1970 185);
DISPLAY 0.787234 (-1970 185);
PAINT MONO (-1970 185);
FORCEPROP 1 LAST PACK_TYPE 0402LF
J 0
(-1935 100);
DISPLAY 0.510638 (-1935 100);
FORCEPROP 1 LAST VALUE 100K
J 0
(-1930 350);
DISPLAY 0.510638 (-1930 350);
FORCEPROP 1 LAST TOLERANCE 1%
J 0
(-1930 300);
DISPLAY 0.510638 (-1930 300);
FORCEPROP 1 LAST WATTAGE 1/16W
J 0
(-1935 250);
DISPLAY 0.510638 (-1935 250);
FORCEPROP 1 LAST MATERIAL EMPTY
J 0
(-1935 200);
DISPLAY 0.510638 (-1935 200);
PAINT RED (-1935 200);
FORCEPROP 2 LAST CDS_LIB pure_quanta
J 0
(-1975 275);
DISPLAY INVISIBLE (-1975 275);
FORCEPROP 1 LAST PATH I62
J 0
(-1925 450);
DISPLAY 0.978723 (-1925 450);
PAINT WHITE (-1925 450);
DISPLAY INVISIBLE (-1925 450);
FORCEPROP 1 LAST PART_NUMBER CS41002FB09
J 0
(-1935 150);
DISPLAY 0.510638 (-1935 150);
DISPLAY INVISIBLE (-1935 150);
FORCEADD UNIVERSAL_GND..1
(-1975 0);
FORCEPROP 3 LASTPIN (-1975 50) SIG_NAME GND\g
J 0
(-1965 60);
DISPLAY 0.659574 (-1965 60);
PAINT MONO (-1965 60);
DISPLAY INVISIBLE (-1965 60);
FORCEPROP 2 LAST CDS_LIB pure_quanta_power
J 0
(-1975 0);
DISPLAY INVISIBLE (-1975 0);
FORCEPROP 1 LAST HDL_POWER GND
J 1
(-1950 -75);
DISPLAY 0.872340 (-1950 -75);
PAINT GREEN (-1950 -75);
DISPLAY INVISIBLE (-1950 -75);
FORCEPROP 1 LAST PATH I63
J 0
(-1900 0);
DISPLAY 0.872340 (-1900 0);
PAINT AQUA (-1900 0);
DISPLAY INVISIBLE (-1900 0);
FORCEADD OFFPAGE..4
R 2
(-2250 475);
FORCEPROP 2 LAST $XR0 81 
J 0
(-2501 475);
DISPLAY 0.638298 (-2501 475);
PAINT MONO (-2501 475);
FORCEPROP 2 LAST CDS_LIB standard
J 0
(-2250 475);
DISPLAY INVISIBLE (-2250 475);
FORCEPROP 1 LAST OFFPAGE TRUE
J 2
(-2575 350);
DISPLAY 0.872340 (-2575 350);
PAINT GREEN (-2575 350);
DISPLAY INVISIBLE (-2575 350);
FORCEPROP 1 LAST COMMENT_BODY TRUE
J 2
(-2225 375);
DISPLAY 0.872340 (-2225 375);
PAINT GREEN (-2225 375);
DISPLAY INVISIBLE (-2225 375);
FORCEPROP 2 LAST PATH I64
J 0
(-2500 525);
DISPLAY 1.021277 (-2500 525);
DISPLAY INVISIBLE (-2500 525);
FORCEADD UNIVERSAL_GND..1
(-1950 3075);
FORCEPROP 3 LASTPIN (-1950 3125) SIG_NAME GND\g
J 0
(-1940 3135);
DISPLAY 0.659574 (-1940 3135);
PAINT MONO (-1940 3135);
DISPLAY INVISIBLE (-1940 3135);
FORCEPROP 2 LAST CDS_LIB pure_quanta_power
J 0
(-1950 3075);
DISPLAY INVISIBLE (-1950 3075);
FORCEPROP 1 LAST HDL_POWER GND
J 1
(-1925 3000);
DISPLAY 0.872340 (-1925 3000);
PAINT GREEN (-1925 3000);
DISPLAY INVISIBLE (-1925 3000);
FORCEPROP 1 LAST PATH I7
J 0
(-1875 3075);
DISPLAY 0.872340 (-1875 3075);
PAINT AQUA (-1875 3075);
DISPLAY INVISIBLE (-1875 3075);
FORCEADD Q_RES..2
(-1950 3350);
FORCEPROP 1 LAST LOCATION R4163
J 0
(-1905 3475);
DISPLAY 0.978723 (-1905 3475);
FORCEPROP 0 LAST $SEC 1
J 0
(-1900 3525);
DISPLAY 0.680851 (-1900 3525);
PAINT MONO (-1900 3525);
DISPLAY INVISIBLE (-1900 3525);
FORCEPROP 0 LAST CDS_SEC 1
J 0
(-1900 3525);
DISPLAY 1.021277 (-1900 3525);
DISPLAY INVISIBLE (-1900 3525);
FORCEPROP 1 LASTPIN (-1950 3450) $PN 1
J 0
(-1945 3412);
DISPLAY 0.787234 (-1945 3412);
PAINT MONO (-1945 3412);
FORCEPROP 1 LASTPIN (-1950 3250) $PN 2
J 0
(-1945 3260);
DISPLAY 0.787234 (-1945 3260);
PAINT MONO (-1945 3260);
FORCEPROP 1 LAST PACK_TYPE 0402LF
J 0
(-1910 3175);
DISPLAY 0.510638 (-1910 3175);
FORCEPROP 1 LAST WATTAGE 1/16W
J 0
(-1910 3325);
DISPLAY 0.510638 (-1910 3325);
FORCEPROP 1 LAST VALUE 100K
J 0
(-1905 3425);
DISPLAY 0.510638 (-1905 3425);
FORCEPROP 1 LAST TOLERANCE 1%
J 0
(-1905 3375);
DISPLAY 0.510638 (-1905 3375);
FORCEPROP 1 LAST MATERIAL EMPTY
J 0
(-1910 3275);
DISPLAY 0.510638 (-1910 3275);
PAINT RED (-1910 3275);
FORCEPROP 2 LAST CDS_LIB pure_quanta
J 0
(-1950 3350);
DISPLAY INVISIBLE (-1950 3350);
FORCEPROP 1 LAST PATH I8
J 0
(-1900 3525);
DISPLAY 0.978723 (-1900 3525);
PAINT WHITE (-1900 3525);
DISPLAY INVISIBLE (-1900 3525);
FORCEPROP 1 LAST PART_NUMBER CS41002FB09
J 0
(-1910 3225);
DISPLAY 0.510638 (-1910 3225);
DISPLAY INVISIBLE (-1910 3225);
FORCEADD Q_RES..2
(-2000 750);
FORCEPROP 1 LAST LOCATION R4543
J 0
(-1955 875);
DISPLAY 0.978723 (-1955 875);
FORCEPROP 0 LAST $SEC 1
J 0
(-1950 925);
DISPLAY 0.680851 (-1950 925);
PAINT MONO (-1950 925);
DISPLAY INVISIBLE (-1950 925);
FORCEPROP 0 LAST CDS_SEC 1
J 0
(-1950 925);
DISPLAY 1.021277 (-1950 925);
DISPLAY INVISIBLE (-1950 925);
FORCEPROP 1 LASTPIN (-2000 850) $PN 1
J 0
(-1995 812);
DISPLAY 0.787234 (-1995 812);
PAINT MONO (-1995 812);
FORCEPROP 1 LASTPIN (-2000 650) $PN 2
J 0
(-1995 660);
DISPLAY 0.787234 (-1995 660);
PAINT MONO (-1995 660);
FORCEPROP 1 LAST WATTAGE 1/16W
J 0
(-1960 725);
DISPLAY 0.638298 (-1960 725);
FORCEPROP 1 LAST MATERIAL CHIP
J 0
(-1960 675);
DISPLAY 0.638298 (-1960 675);
FORCEPROP 1 LAST PACK_TYPE 0402LF
J 0
(-1960 625);
DISPLAY 0.638298 (-1960 625);
FORCEPROP 1 LAST VALUE 1K
J 0
(-1955 825);
DISPLAY 0.638298 (-1955 825);
FORCEPROP 1 LAST TOLERANCE 1%
J 0
(-1955 775);
DISPLAY 0.638298 (-1955 775);
FORCEPROP 2 LAST CDS_LIB pure_quanta
J 0
(-2000 750);
DISPLAY INVISIBLE (-2000 750);
FORCEPROP 1 LAST PATH I85
J 0
(-1950 925);
DISPLAY 0.978723 (-1950 925);
PAINT WHITE (-1950 925);
DISPLAY INVISIBLE (-1950 925);
FORCEPROP 1 LAST PART_NUMBER CS21002FB06
J 0
(-1960 575);
DISPLAY 0.638298 (-1960 575);
DISPLAY INVISIBLE (-1960 575);
FORCEADD 74LVC2G17GW..1
(3975 4600);
FORCEPROP 1 LAST LOCATION U316
J 0
(4202 4360);
DISPLAY 0.723404 (4202 4360);
PAINT GREEN (4202 4360);
FORCEPROP 2 LAST SEC 1
J 0
(4225 4400);
DISPLAY 0.680851 (4225 4400);
PAINT MONO (4225 4400);
DISPLAY INVISIBLE (4225 4400);
FORCEPROP 2 LASTPIN (3600 4725) $PN 1
J 2
(3590 4735);
DISPLAY 0.680851 (3590 4735);
PAINT MONO (3590 4735);
FORCEPROP 2 LASTPIN (3600 4475) $PN 3
J 2
(3590 4485);
DISPLAY 0.680851 (3590 4485);
PAINT MONO (3590 4485);
FORCEPROP 2 LASTPIN (4350 4725) $PN 6
J 0
(4360 4735);
DISPLAY 0.680851 (4360 4735);
PAINT MONO (4360 4735);
FORCEPROP 2 LASTPIN (4350 4475) $PN 4
J 0
(4360 4485);
DISPLAY 0.680851 (4360 4485);
PAINT MONO (4360 4485);
FORCEPROP 2 LASTPIN (4000 4175) $PN 2
R 1
J 2
(3990 4165);
DISPLAY 0.680851 (3990 4165);
PAINT MONO (3990 4165);
FORCEPROP 2 LASTPIN (4000 5025) $PN 5
R 1
J 0
(3990 5035);
DISPLAY 0.680851 (3990 5035);
PAINT MONO (3990 5035);
FORCEPROP 1 LAST MATERIAL IC
J 0
(3775 3775);
DISPLAY 0.723404 (3775 3775);
PAINT GREEN (3775 3775);
FORCEPROP 2 LAST PART_TYPE SMLF
J 0
(3775 3925);
DISPLAY 1.021277 (3775 3925);
FORCEPROP 2 LAST VALUE 74LVC2G17GW
J 0
(3775 3875);
DISPLAY 1.021277 (3775 3875);
FORCEPROP 2 LAST SEC_TYPE 
J 0
(4225 4400);
DISPLAY 1.021277 (4225 4400);
DISPLAY INVISIBLE (4225 4400);
FORCEPROP 2 LAST CDS_LIB pure_quanta
J 0
(3975 4600);
DISPLAY INVISIBLE (3975 4600);
FORCEPROP 1 LAST CDS_LMAN_SYM_OUTLINE -225,275,225,-275
J 0
(3975 4600);
DISPLAY 0.468085 (3975 4600);
PAINT GREEN (3975 4600);
DISPLAY INVISIBLE (3975 4600);
FORCEPROP 1 LAST NEEDS_NO_SIZE TRUE
J 0
(4200 4599);
DISPLAY 0.468085 (4200 4599);
PAINT GREEN (4200 4599);
DISPLAY INVISIBLE (4200 4599);
FORCEPROP 1 LAST PATH I86
J 0
(4200 4325);
DISPLAY 0.723404 (4200 4325);
PAINT GREEN (4200 4325);
DISPLAY INVISIBLE (4200 4325);
FORCEPROP 1 LAST PART_NUMBER AL2G0017005
J 0
(3800 3825);
DISPLAY 0.723404 (3800 3825);
PAINT GREEN (3800 3825);
DISPLAY INVISIBLE (3800 3825);
FORCEADD Q_RES..2
(2400 5075);
FORCEPROP 1 LAST LOCATION R4548
J 0
(2445 5200);
DISPLAY 0.978723 (2445 5200);
FORCEPROP 0 LAST $SEC 1
J 0
(2450 5250);
DISPLAY 0.680851 (2450 5250);
PAINT MONO (2450 5250);
DISPLAY INVISIBLE (2450 5250);
FORCEPROP 0 LAST CDS_SEC 1
J 0
(2450 5250);
DISPLAY 1.021277 (2450 5250);
DISPLAY INVISIBLE (2450 5250);
FORCEPROP 1 LASTPIN (2400 5175) $PN 1
J 0
(2405 5137);
DISPLAY 0.787234 (2405 5137);
PAINT MONO (2405 5137);
FORCEPROP 1 LASTPIN (2400 4975) $PN 2
J 0
(2405 4985);
DISPLAY 0.787234 (2405 4985);
PAINT MONO (2405 4985);
FORCEPROP 1 LAST VALUE 100K
J 0
(2445 5150);
DISPLAY 0.510638 (2445 5150);
FORCEPROP 1 LAST WATTAGE 1/16W
J 0
(2440 5050);
DISPLAY 0.510638 (2440 5050);
FORCEPROP 1 LAST MATERIAL CHIP
J 0
(2440 5000);
DISPLAY 0.510638 (2440 5000);
FORCEPROP 1 LAST PACK_TYPE 0402LF
J 0
(2440 4900);
DISPLAY 0.510638 (2440 4900);
FORCEPROP 1 LAST TOLERANCE 1%
J 0
(2445 5100);
DISPLAY 0.510638 (2445 5100);
FORCEPROP 2 LAST CDS_LIB pure_quanta
J 0
(2400 5075);
DISPLAY INVISIBLE (2400 5075);
FORCEPROP 1 LAST PATH I87
J 0
(2450 5250);
DISPLAY 0.978723 (2450 5250);
PAINT WHITE (2450 5250);
DISPLAY INVISIBLE (2450 5250);
FORCEPROP 1 LAST PART_NUMBER CS41002FB09
J 0
(2440 4950);
DISPLAY 0.510638 (2440 4950);
DISPLAY INVISIBLE (2440 4950);
FORCEADD UNIVERSAL_POWER..1
(2375 5800);
FORCEPROP 3 LASTPIN (2375 5750) SIG_NAME P3V3_AUX\g
J 0
(2385 5760);
DISPLAY 0.659574 (2385 5760);
PAINT MONO (2385 5760);
DISPLAY INVISIBLE (2385 5760);
FORCEPROP 1 LAST HDL_POWER P3V3_AUX
J 1
(2375 5850);
DISPLAY 0.872340 (2375 5850);
PAINT GREEN (2375 5850);
FORCEPROP 2 LAST CDS_LIB pure_quanta_power
J 0
(2375 5800);
PAINT MONO (2375 5800);
DISPLAY INVISIBLE (2375 5800);
FORCEPROP 1 LAST PATH I88
J 0
(2425 5825);
DISPLAY 0.872340 (2425 5825);
PAINT AQUA (2425 5825);
DISPLAY INVISIBLE (2425 5825);
FORCEADD Q_RES..2
(2375 5550);
FORCEPROP 1 LAST LOCATION R4547
J 0
(2420 5675);
DISPLAY 0.978723 (2420 5675);
FORCEPROP 0 LAST $SEC 1
J 0
(2425 5725);
DISPLAY 0.680851 (2425 5725);
PAINT MONO (2425 5725);
DISPLAY INVISIBLE (2425 5725);
FORCEPROP 0 LAST CDS_SEC 1
J 0
(2425 5725);
DISPLAY 1.021277 (2425 5725);
DISPLAY INVISIBLE (2425 5725);
FORCEPROP 1 LASTPIN (2375 5650) $PN 1
J 0
(2380 5612);
DISPLAY 0.787234 (2380 5612);
PAINT MONO (2380 5612);
FORCEPROP 1 LASTPIN (2375 5450) $PN 2
J 0
(2380 5460);
DISPLAY 0.787234 (2380 5460);
PAINT MONO (2380 5460);
FORCEPROP 1 LAST PACK_TYPE 0402LF
J 0
(2415 5375);
DISPLAY 0.510638 (2415 5375);
FORCEPROP 1 LAST VALUE 100K
J 0
(2420 5625);
DISPLAY 0.510638 (2420 5625);
FORCEPROP 1 LAST TOLERANCE 1%
J 0
(2420 5575);
DISPLAY 0.510638 (2420 5575);
FORCEPROP 1 LAST WATTAGE 1/16W
J 0
(2415 5525);
DISPLAY 0.510638 (2415 5525);
FORCEPROP 1 LAST MATERIAL EMPTY
J 0
(2415 5475);
DISPLAY 0.510638 (2415 5475);
PAINT RED (2415 5475);
FORCEPROP 2 LAST CDS_LIB pure_quanta
J 0
(2375 5550);
DISPLAY INVISIBLE (2375 5550);
FORCEPROP 1 LAST PATH I89
J 0
(2425 5725);
DISPLAY 0.978723 (2425 5725);
PAINT WHITE (2425 5725);
DISPLAY INVISIBLE (2425 5725);
FORCEPROP 1 LAST PART_NUMBER CS41002FB09
J 0
(2415 5425);
DISPLAY 0.510638 (2415 5425);
DISPLAY INVISIBLE (2415 5425);
FORCEADD Q_RES..2
(-1975 3825);
FORCEPROP 1 LAST LOCATION R4162
J 0
(-1930 3950);
DISPLAY 0.978723 (-1930 3950);
FORCEPROP 0 LAST $SEC 1
J 0
(-1925 4000);
DISPLAY 0.680851 (-1925 4000);
PAINT MONO (-1925 4000);
DISPLAY INVISIBLE (-1925 4000);
FORCEPROP 0 LAST CDS_SEC 1
J 0
(-1925 4000);
DISPLAY 1.021277 (-1925 4000);
DISPLAY INVISIBLE (-1925 4000);
FORCEPROP 1 LASTPIN (-1975 3925) $PN 1
J 0
(-1970 3887);
DISPLAY 0.787234 (-1970 3887);
PAINT MONO (-1970 3887);
FORCEPROP 1 LASTPIN (-1975 3725) $PN 2
J 0
(-1970 3735);
DISPLAY 0.787234 (-1970 3735);
PAINT MONO (-1970 3735);
FORCEPROP 1 LAST TOLERANCE 1%
J 0
(-1930 3850);
DISPLAY 0.787234 (-1930 3850);
FORCEPROP 1 LAST VALUE 54.9K
J 0
(-1930 3900);
DISPLAY 0.787234 (-1930 3900);
FORCEPROP 1 LAST WATTAGE 1/16W
J 0
(-1935 3800);
DISPLAY 0.787234 (-1935 3800);
FORCEPROP 1 LAST MATERIAL EMPTY
J 0
(-1935 3750);
DISPLAY 0.787234 (-1935 3750);
PAINT RED (-1935 3750);
FORCEPROP 1 LAST PACK_TYPE 0402LF
J 0
(-1935 3650);
DISPLAY 0.787234 (-1935 3650);
FORCEPROP 2 LAST CDS_LIB pure_quanta
J 0
(-1975 3825);
DISPLAY INVISIBLE (-1975 3825);
FORCEPROP 1 LAST PATH I9
J 0
(-1925 4000);
DISPLAY 0.978723 (-1925 4000);
PAINT WHITE (-1925 4000);
DISPLAY INVISIBLE (-1925 4000);
FORCEPROP 1 LAST PART_NUMBER CS35492FB03
J 0
(-1935 3700);
DISPLAY 0.787234 (-1935 3700);
DISPLAY INVISIBLE (-1935 3700);
FORCEADD UNIVERSAL_GND..1
(2400 4900);
FORCEPROP 3 LASTPIN (2400 4950) SIG_NAME GND\g
J 0
(2410 4960);
DISPLAY 0.659574 (2410 4960);
PAINT MONO (2410 4960);
DISPLAY INVISIBLE (2410 4960);
FORCEPROP 2 LAST CDS_LIB pure_quanta_power
J 0
(2400 4900);
DISPLAY INVISIBLE (2400 4900);
FORCEPROP 1 LAST HDL_POWER GND
J 1
(2425 4825);
DISPLAY 0.872340 (2425 4825);
PAINT GREEN (2425 4825);
DISPLAY INVISIBLE (2425 4825);
FORCEPROP 1 LAST PATH I90
J 0
(2475 4900);
DISPLAY 0.872340 (2475 4900);
PAINT AQUA (2475 4900);
DISPLAY INVISIBLE (2475 4900);
FORCEADD OFFPAGE..4
R 2
(2200 5275);
FORCEPROP 2 LAST $XR0 81 
J 0
(1979 5275);
DISPLAY 0.638298 (1979 5275);
PAINT MONO (1979 5275);
FORCEPROP 2 LAST CDS_LIB standard
J 0
(2200 5275);
DISPLAY INVISIBLE (2200 5275);
FORCEPROP 1 LAST OFFPAGE TRUE
J 2
(1875 5150);
DISPLAY 0.872340 (1875 5150);
PAINT GREEN (1875 5150);
DISPLAY INVISIBLE (1875 5150);
FORCEPROP 1 LAST COMMENT_BODY TRUE
J 2
(2225 5175);
DISPLAY 0.872340 (2225 5175);
PAINT GREEN (2225 5175);
DISPLAY INVISIBLE (2225 5175);
FORCEPROP 2 LAST PATH I91
J 0
(1950 5325);
DISPLAY 1.021277 (1950 5325);
DISPLAY INVISIBLE (1950 5325);
FORCEADD UNIVERSAL_GND..1
(4100 5225);
FORCEPROP 3 LASTPIN (4100 5275) SIG_NAME GND\g
J 0
(4110 5285);
DISPLAY 0.659574 (4110 5285);
PAINT MONO (4110 5285);
DISPLAY INVISIBLE (4110 5285);
FORCEPROP 2 LAST CDS_LIB pure_quanta_power
J 0
(4100 5225);
PAINT MONO (4100 5225);
DISPLAY INVISIBLE (4100 5225);
FORCEPROP 1 LAST HDL_POWER GND
J 1
(4125 5150);
DISPLAY 0.872340 (4125 5150);
PAINT GREEN (4125 5150);
DISPLAY INVISIBLE (4125 5150);
FORCEPROP 1 LAST PATH I92
J 0
(4175 5225);
DISPLAY 0.872340 (4175 5225);
PAINT AQUA (4175 5225);
DISPLAY INVISIBLE (4175 5225);
FORCEADD Q_CAP..1
(4100 5425);
FORCEPROP 1 LAST LOCATION C8
J 0
(4150 5525);
DISPLAY 0.787234 (4150 5525);
FORCEPROP 2 LAST $SEC 1
J 0
(4150 5625);
DISPLAY 0.680851 (4150 5625);
PAINT MONO (4150 5625);
DISPLAY INVISIBLE (4150 5625);
FORCEPROP 2 LAST CDS_SEC 1
J 0
(4150 5625);
DISPLAY 1.021277 (4150 5625);
DISPLAY INVISIBLE (4150 5625);
FORCEPROP 1 LASTPIN (4100 5525) $PN 1
J 0
(4110 5505);
DISPLAY 0.787234 (4110 5505);
FORCEPROP 1 LASTPIN (4100 5325) $PN 2
J 0
(4110 5305);
DISPLAY 0.787234 (4110 5305);
FORCEPROP 1 LAST TOLERANCE 10%
J 0
(4150 5375);
DISPLAY 0.510638 (4150 5375);
FORCEPROP 1 LAST PACK_TYPE 0402
J 0
(4150 5225);
DISPLAY 0.510638 (4150 5225);
FORCEPROP 1 LAST MATERIAL X7R
J 0
(4150 5325);
DISPLAY 0.510638 (4150 5325);
FORCEPROP 1 LAST VOLTAGE 25V
J 0
(4150 5425);
DISPLAY 0.510638 (4150 5425);
FORCEPROP 1 LAST VALUE 0.1UF
J 0
(4150 5475);
DISPLAY 0.510638 (4150 5475);
FORCEPROP 2 LAST CDS_LIB pure_quanta
J 2
(4100 5425);
PAINT MONO (4100 5425);
DISPLAY INVISIBLE (4100 5425);
FORCEPROP 1 LAST PATH I93
J 0
(4150 5575);
DISPLAY 0.978723 (4150 5575);
PAINT WHITE (4150 5575);
DISPLAY INVISIBLE (4150 5575);
FORCEPROP 1 LAST PART_NUMBER CH4104K1B00
J 0
(4150 5275);
DISPLAY 0.510638 (4150 5275);
DISPLAY INVISIBLE (4150 5275);
FORCEADD UNIVERSAL_POWER..1
(4100 5675);
FORCEPROP 3 LASTPIN (4100 5625) SIG_NAME P3V3_AUX\g
J 0
(4110 5635);
DISPLAY 0.659574 (4110 5635);
PAINT MONO (4110 5635);
DISPLAY INVISIBLE (4110 5635);
FORCEPROP 1 LAST HDL_POWER P3V3_AUX
J 1
(4100 5725);
DISPLAY 0.872340 (4100 5725);
PAINT GREEN (4100 5725);
FORCEPROP 2 LAST CDS_LIB pure_quanta_power
J 0
(4100 5675);
PAINT MONO (4100 5675);
DISPLAY INVISIBLE (4100 5675);
FORCEPROP 1 LAST PATH I94
J 0
(4150 5700);
DISPLAY 0.872340 (4150 5700);
PAINT AQUA (4150 5700);
DISPLAY INVISIBLE (4150 5700);
FORCEADD OFFPAGE..2
(6200 5275);
FORCEPROP 2 LAST $XR0 117 
J 0
(6389 5275);
DISPLAY 0.638298 (6389 5275);
PAINT MONO (6389 5275);
FORCEPROP 2 LAST CDS_LIB standard
J 0
(6200 5275);
DISPLAY INVISIBLE (6200 5275);
FORCEPROP 1 LAST OFFPAGE TRUE
J 0
(6525 5150);
DISPLAY 0.872340 (6525 5150);
PAINT AQUA (6525 5150);
DISPLAY INVISIBLE (6525 5150);
FORCEPROP 1 LAST COMMENT_BODY TRUE
J 0
(6155 5180);
DISPLAY 0.872340 (6155 5180);
PAINT GREEN (6155 5180);
DISPLAY INVISIBLE (6155 5180);
FORCEPROP 2 LAST PATH I95
J 0
(6400 5325);
DISPLAY 1.021277 (6400 5325);
DISPLAY INVISIBLE (6400 5325);
FORCEADD UNIVERSAL_POWER..1
(5125 5775);
FORCEPROP 3 LASTPIN (5125 5725) SIG_NAME P3V3_AUX\g
J 0
(5135 5735);
DISPLAY 0.659574 (5135 5735);
PAINT MONO (5135 5735);
DISPLAY INVISIBLE (5135 5735);
FORCEPROP 1 LAST HDL_POWER P3V3_AUX
J 1
(5125 5825);
DISPLAY 0.872340 (5125 5825);
PAINT GREEN (5125 5825);
FORCEPROP 2 LAST CDS_LIB pure_quanta_power
J 0
(5125 5775);
PAINT MONO (5125 5775);
DISPLAY INVISIBLE (5125 5775);
FORCEPROP 1 LAST PATH I96
J 0
(5175 5800);
DISPLAY 0.872340 (5175 5800);
PAINT AQUA (5175 5800);
DISPLAY INVISIBLE (5175 5800);
FORCEADD Q_RES..1
(5375 5275);
FORCEPROP 1 LAST LOCATION R4550
J 0
(5150 5275);
DISPLAY 0.787234 (5150 5275);
FORCEPROP 0 LAST $SEC 1
J 0
(5325 5375);
DISPLAY 0.680851 (5325 5375);
PAINT MONO (5325 5375);
DISPLAY INVISIBLE (5325 5375);
FORCEPROP 0 LAST CDS_SEC 1
J 0
(5325 5375);
DISPLAY 1.021277 (5325 5375);
DISPLAY INVISIBLE (5325 5375);
FORCEPROP 1 LASTPIN (5275 5275) $PN 1
J 0
(5287 5287);
DISPLAY 0.787234 (5287 5287);
PAINT MONO (5287 5287);
FORCEPROP 1 LASTPIN (5475 5275) $PN 2
J 0
(5437 5287);
DISPLAY 0.787234 (5437 5287);
PAINT MONO (5437 5287);
FORCEPROP 1 LAST PACK_TYPE 0402LF
J 0
(5200 5225);
DISPLAY 0.723404 (5200 5225);
FORCEPROP 1 LAST VALUE 49.9
J 2
(5650 5275);
DISPLAY 0.723404 (5650 5275);
FORCEPROP 1 LAST MATERIAL CHIP
J 0
(5400 5225);
DISPLAY 0.723404 (5400 5225);
FORCEPROP 2 LAST CDS_LIB pure_quanta
J 0
(5375 5275);
DISPLAY INVISIBLE (5375 5275);
FORCEPROP 1 LAST WATTAGE 1/16W
J 2
(5775 5225);
DISPLAY 0.723404 (5775 5225);
PAINT SKYBLUE (5775 5225);
DISPLAY INVISIBLE (5775 5225);
FORCEPROP 1 LAST TOLERANCE 1%
J 0
(5850 5275);
DISPLAY 0.723404 (5850 5275);
PAINT SKYBLUE (5850 5275);
DISPLAY INVISIBLE (5850 5275);
FORCEPROP 1 LAST PATH I97
J 0
(5325 5425);
DISPLAY 0.978723 (5325 5425);
PAINT WHITE (5325 5425);
DISPLAY INVISIBLE (5325 5425);
FORCEPROP 1 LAST PART_NUMBER CS04992FB07
J 0
(4975 5175);
DISPLAY 0.723404 (4975 5175);
PAINT WHITE (4975 5175);
DISPLAY INVISIBLE (4975 5175);
FORCEADD Q_RES..2
(5125 5525);
FORCEPROP 1 LAST LOCATION R4549
J 0
(5170 5650);
DISPLAY 0.638298 (5170 5650);
FORCEPROP 2 LAST $SEC 1
J 0
(5175 5750);
DISPLAY 0.680851 (5175 5750);
PAINT MONO (5175 5750);
DISPLAY INVISIBLE (5175 5750);
FORCEPROP 2 LAST CDS_SEC 1
J 0
(5175 5750);
DISPLAY 1.021277 (5175 5750);
DISPLAY INVISIBLE (5175 5750);
FORCEPROP 1 LASTPIN (5125 5625) $PN 1
J 0
(5130 5587);
DISPLAY 0.787234 (5130 5587);
FORCEPROP 1 LASTPIN (5125 5425) $PN 2
J 0
(5130 5435);
DISPLAY 0.787234 (5130 5435);
FORCEPROP 1 LAST MATERIAL EMPTY
J 0
(5165 5450);
DISPLAY 0.638298 (5165 5450);
PAINT RED (5165 5450);
FORCEPROP 1 LAST WATTAGE 1/16W
J 0
(5165 5500);
DISPLAY 0.638298 (5165 5500);
FORCEPROP 1 LAST TOLERANCE 5%
J 0
(5170 5550);
DISPLAY 0.638298 (5170 5550);
FORCEPROP 1 LAST VALUE 4.7K
J 0
(5170 5600);
DISPLAY 0.638298 (5170 5600);
FORCEPROP 1 LAST PACK_TYPE 0402LF
J 0
(5165 5400);
DISPLAY 0.638298 (5165 5400);
FORCEPROP 2 LAST CDS_LIB pure_quanta
J 0
(5125 5525);
PAINT MONO (5125 5525);
DISPLAY INVISIBLE (5125 5525);
FORCEPROP 1 LAST PATH I98
J 0
(5175 5700);
DISPLAY 0.978723 (5175 5700);
PAINT WHITE (5175 5700);
DISPLAY INVISIBLE (5175 5700);
FORCEPROP 1 LAST PART_NUMBER CS24702JB10
J 0
(5165 5350);
DISPLAY 0.638298 (5165 5350);
DISPLAY INVISIBLE (5165 5350);
FORCEADD Q_RES..2
(5175 5000);
FORCEPROP 1 LAST LOCATION R4555
J 0
(5220 5125);
DISPLAY 0.978723 (5220 5125);
FORCEPROP 0 LAST $SEC 1
J 0
(5225 5175);
DISPLAY 0.680851 (5225 5175);
PAINT MONO (5225 5175);
DISPLAY INVISIBLE (5225 5175);
FORCEPROP 0 LAST CDS_SEC 1
J 0
(5225 5175);
DISPLAY 1.021277 (5225 5175);
DISPLAY INVISIBLE (5225 5175);
FORCEPROP 1 LASTPIN (5175 5100) $PN 1
J 0
(5180 5062);
DISPLAY 0.787234 (5180 5062);
PAINT MONO (5180 5062);
FORCEPROP 1 LASTPIN (5175 4900) $PN 2
J 0
(5180 4910);
DISPLAY 0.787234 (5180 4910);
PAINT MONO (5180 4910);
FORCEPROP 1 LAST WATTAGE 1/16W
J 0
(5215 4975);
DISPLAY 0.638298 (5215 4975);
FORCEPROP 1 LAST VALUE 4.7K
J 0
(5220 5075);
DISPLAY 0.638298 (5220 5075);
FORCEPROP 1 LAST TOLERANCE 5%
J 0
(5220 5025);
DISPLAY 0.638298 (5220 5025);
FORCEPROP 1 LAST PACK_TYPE 0402LF
J 0
(5215 4875);
DISPLAY 0.638298 (5215 4875);
FORCEPROP 1 LAST MATERIAL EMPTY
J 0
(5215 4925);
DISPLAY 0.638298 (5215 4925);
PAINT RED (5215 4925);
FORCEPROP 2 LAST CDS_LIB pure_quanta
J 0
(5175 5000);
DISPLAY INVISIBLE (5175 5000);
FORCEPROP 1 LAST PATH I99
J 0
(5225 5175);
DISPLAY 0.978723 (5225 5175);
PAINT WHITE (5225 5175);
DISPLAY INVISIBLE (5225 5175);
FORCEPROP 1 LAST PART_NUMBER CS24702JB10
J 0
(5215 4825);
DISPLAY 0.638298 (5215 4825);
DISPLAY INVISIBLE (5215 4825);
FORCEADD DNS..2
(-2000 2350);
PAINT RED (-2000 2350);
FORCEPROP 2 LAST CDS_LIB mstr_misc
J 0
(-2000 2350);
DISPLAY INVISIBLE (-2000 2350);
FORCEPROP 1 LAST COMMENT_BODY TRUE
J 0
(-2000 2350);
DISPLAY INVISIBLE (-2000 2350);
FORCEADD DNS..2
(-1950 3325);
PAINT RED (-1950 3325);
FORCEPROP 2 LAST CDS_LIB mstr_misc
J 0
(-1950 3325);
DISPLAY INVISIBLE (-1950 3325);
FORCEPROP 1 LAST COMMENT_BODY TRUE
J 0
(-1950 3325);
DISPLAY INVISIBLE (-1950 3325);
FORCEADD DNS..2
(-1975 4700);
PAINT RED (-1975 4700);
FORCEPROP 2 LAST CDS_LIB mstr_misc
J 0
(-1975 4700);
DISPLAY INVISIBLE (-1975 4700);
FORCEPROP 1 LAST COMMENT_BODY TRUE
J 0
(-1975 4700);
DISPLAY INVISIBLE (-1975 4700);
FORCEADD DNS..2
(-1975 3800);
PAINT RED (-1975 3800);
FORCEPROP 2 LAST CDS_LIB mstr_misc
J 0
(-1975 3800);
DISPLAY INVISIBLE (-1975 3800);
FORCEPROP 1 LAST COMMENT_BODY TRUE
J 0
(-1975 3800);
DISPLAY INVISIBLE (-1975 3800);
FORCEADD DNS..2
(-2000 5175);
PAINT RED (-2000 5175);
FORCEPROP 2 LAST CDS_LIB mstr_misc
J 0
(-2000 5175);
DISPLAY INVISIBLE (-2000 5175);
FORCEPROP 1 LAST COMMENT_BODY TRUE
J 0
(-2000 5175);
DISPLAY INVISIBLE (-2000 5175);
FORCEADD QUANTA_TITLE_BLOCK_C..1
(6550 -250);
FORCEPROP 0 LAST CDS_CON_LAST_MODIFIED Thu Sep 14 16:12:23 2023
J 0
(4665 -235);
PAINT MONO (4665 -235);
DISPLAY INVISIBLE (4665 -235);
FORCEPROP 1 LAST CUSTOM_TXT_CDS <CON_LAST_MODIFIED>
J 0
(4665 -235);
DISPLAY 0.978723 (4665 -235);
FORCEPROP 2 LAST CUSTOM_TXT_CDS <XR_PAGE_TITLE>
J 0
(-1340 5000);
DISPLAY 0.638298 (-1340 5000);
PAINT PINK (-1340 5000);
DISPLAY INVISIBLE (-1340 5000);
FORCEPROP 2 LAST CUSTOM_TXT_CDS <Q_NUMBER>
J 0
(5147 -147);
DISPLAY 1.212766 (5147 -147);
FORCEPROP 1 LAST CUSTOM_TXT_CDS <NAME_2>
J 0
(3375 -200);
FORCEPROP 1 LAST CUSTOM_TXT_CDS <NAME_1>
J 0
(3375 -75);
FORCEPROP 1 LAST CUSTOM_TXT_CDS <Q_PROJ>
J 0
(4168 -148);
DISPLAY 1.212766 (4168 -148);
FORCEPROP 1 LAST CUSTOM_TXT_CDS <Q_REV>
J 0
(6366 -147);
DISPLAY 1.212766 (6366 -147);
FORCEPROP 1 LAST CUSTOM_TXT_CDS <CON_PAGE_NUM> OF <CON_TOTAL_PAGES>
J 0
(6104 -232);
DISPLAY 0.978723 (6104 -232);
FORCEPROP 1 LAST Q_TITLE EXAMAX_ISO (1/7)
J 0
(-2816 -224);
DISPLAY 1.957447 (-2816 -224);
PAINT GREEN (-2816 -224);
FORCEPROP 2 LAST PAGE_BORDER TRUE
J 0
(-1340 5000);
DISPLAY 0.638298 (-1340 5000);
PAINT PINK (-1340 5000);
DISPLAY INVISIBLE (-1340 5000);
FORCEPROP 1 LAST CDS_LMAN_SYM_OUTLINE -9475,6775,100,-125
J 0
(6550 -250);
DISPLAY 0.468085 (6550 -250);
PAINT GREEN (6550 -250);
DISPLAY INVISIBLE (6550 -250);
FORCEPROP 2 LAST CDS_LIB pure_quanta
J 0
(6550 -250);
PAINT MONO (6550 -250);
DISPLAY INVISIBLE (6550 -250);
FORCEPROP 2 LAST CDS_XR_PAGE_TITLE CR-124 : @T6G_MB_LIB.T6G(SCH_1):PAGE124
J 0
(-1340 5000);
DISPLAY 0.638298 (-1340 5000);
PAINT PINK (-1340 5000);
DISPLAY INVISIBLE (-1340 5000);
FORCEPROP 1 LAST Q_DEPT BU9
J 1
(2787 -201);
DISPLAY 1.957447 (2787 -201);
PAINT GREEN (2787 -201);
DISPLAY INVISIBLE (2787 -201);
FORCEPROP 1 LAST COMMENT_BODY TRUE
J 0
(6562 -263);
DISPLAY 0.978723 (6562 -263);
PAINT GREEN (6562 -263);
DISPLAY INVISIBLE (6562 -263);
FORCEADD DNS..2
(-1975 1875);
PAINT RED (-1975 1875);
FORCEPROP 2 LAST CDS_LIB mstr_misc
J 0
(-1975 1875);
DISPLAY INVISIBLE (-1975 1875);
FORCEPROP 1 LAST COMMENT_BODY TRUE
J 0
(-1975 1875);
DISPLAY INVISIBLE (-1975 1875);
FORCEADD DNS..2
(-1975 250);
PAINT RED (-1975 250);
FORCEPROP 2 LAST CDS_LIB mstr_misc
J 0
(-1975 250);
DISPLAY INVISIBLE (-1975 250);
FORCEPROP 1 LAST COMMENT_BODY TRUE
J 0
(-1975 250);
DISPLAY INVISIBLE (-1975 250);
FORCEADD DNS..2
(-625 6050);
PAINT RED (-625 6050);
FORCEPROP 2 LAST CDS_LIB mstr_misc
J 0
(-625 6050);
DISPLAY INVISIBLE (-625 6050);
FORCEPROP 1 LAST COMMENT_BODY TRUE
J 0
(-625 6050);
DISPLAY INVISIBLE (-625 6050);
FORCEADD DNS..2
(-400 3125);
PAINT RED (-400 3125);
FORCEPROP 2 LAST CDS_LIB mstr_misc
J 0
(-400 3125);
DISPLAY INVISIBLE (-400 3125);
FORCEPROP 1 LAST COMMENT_BODY TRUE
J 0
(-400 3125);
DISPLAY INVISIBLE (-400 3125);
FORCEADD DNS..2
(-400 4575);
PAINT RED (-400 4575);
FORCEPROP 2 LAST CDS_LIB mstr_misc
J 0
(-400 4575);
DISPLAY INVISIBLE (-400 4575);
FORCEPROP 1 LAST COMMENT_BODY TRUE
J 0
(-400 4575);
DISPLAY INVISIBLE (-400 4575);
FORCEADD DNS..2
(1200 800);
PAINT RED (1200 800);
FORCEPROP 2 LAST CDS_LIB mstr_misc
J 0
(1200 800);
DISPLAY INVISIBLE (1200 800);
FORCEPROP 1 LAST COMMENT_BODY TRUE
J 0
(1200 800);
DISPLAY INVISIBLE (1200 800);
FORCEADD DNS..2
(5125 5500);
PAINT RED (5125 5500);
FORCEPROP 2 LAST CDS_LIB mstr_misc
J 0
(5125 5500);
DISPLAY INVISIBLE (5125 5500);
FORCEPROP 1 LAST COMMENT_BODY TRUE
J 0
(5125 5500);
DISPLAY INVISIBLE (5125 5500);
FORCEADD DNS..2
(2375 5525);
PAINT RED (2375 5525);
FORCEPROP 2 LAST CDS_LIB mstr_misc
J 0
(2375 5525);
DISPLAY INVISIBLE (2375 5525);
FORCEPROP 1 LAST COMMENT_BODY TRUE
J 0
(2375 5525);
DISPLAY INVISIBLE (2375 5525);
FORCEADD DNS..2
(5175 4950);
PAINT RED (5175 4950);
FORCEPROP 2 LAST CDS_LIB mstr_misc
J 0
(5175 4950);
DISPLAY INVISIBLE (5175 4950);
FORCEPROP 1 LAST COMMENT_BODY TRUE
J 0
(5175 4950);
DISPLAY INVISIBLE (5175 4950);
FORCEADD DNS..2
(325 1225);
PAINT RED (325 1225);
FORCEPROP 2 LAST CDS_LIB mstr_misc
J 0
(325 1225);
DISPLAY INVISIBLE (325 1225);
FORCEPROP 1 LAST COMMENT_BODY TRUE
J 0
(325 1225);
DISPLAY INVISIBLE (325 1225);
WIRE 16 -1 (-1975 4025)(-1975 3925);
WIRE 16 -1 (5175 4900)(5175 4825);
WIRE 16 -1 (4000 4050)(4000 4175);
WIRE 16 -1 (3600 4475)(3300 4475);
WIRE 16 -1 (3300 4475)(3300 4275);
WIRE 16 -1 (-1975 4625)(-1975 4500);
WIRE 16 -1 (-2000 5400)(-2000 5300);
WIRE 16 -1 (-825 1950)(-825 1825);
WIRE 16 -1 (-825 2925)(-825 2850);
WIRE 16 -1 (-800 3400)(-800 3275);
WIRE 16 -1 (-800 4375)(-800 4300);
WIRE 16 -1 (-825 4775)(-825 4650);
WIRE 16 -1 (-1975 1800)(-1975 1675);
WIRE 16 -1 (-825 5750)(-825 5675);
WIRE 16 -1 (325 5075)(325 4950);
WIRE 16 -1 (325 2250)(325 2125);
WIRE 16 -1 (1100 2300)(1100 2250);
WIRE 16 -1 (325 3050)(325 2975);
WIRE 16 -1 (350 3700)(350 3575);
WIRE 16 -1 (350 4500)(350 4425);
WIRE 16 -1 (1125 3750)(1125 3700);
WIRE 16 -1 (1100 5125)(1100 5075);
WIRE 16 -1 (325 5875)(325 5800);
WIRE 16 -1 (325 1425)(325 1350);
WIRE 16 -1 (1100 675)(1100 625);
WIRE 16 -1 (325 625)(325 500);
WIRE 16 -1 (-825 1300)(-825 1225);
WIRE 16 -1 (-2000 950)(-2000 850);
WIRE 16 -1 (-2000 2575)(-2000 2475);
WIRE 16 -1 (-825 325)(-825 200);
WIRE 16 -1 (-1975 175)(-1975 50);
WIRE 16 -1 (-1950 3250)(-1950 3125);
WIRE 16 -1 (2375 5750)(2375 5650);
WIRE 16 -1 (2400 4975)(2400 4950);
WIRE 16 -1 (4100 5325)(4100 5275);
WIRE 16 -1 (5125 5725)(5125 5625);
WIRE 16 -1 (-825 2350)(-825 2400);
WIRE 16 -1 (75 2400)(-825 2400);
FORCEPROP 2 LAST SIG_NAME GPU_3V3IO_RSVD4_N
J 0
(-760 2410);
DISPLAY 0.808511 (-760 2410);
FORCEPROP 2 LASTPROP $XRERR UNIQUE?
J 0
(-1000 2410);
DISPLAY 0.638298 (-1000 2410);
PAINT MONO (-1000 2410);
DISPLAY INVISIBLE (-1000 2410);
WIRE 16 -1 (-825 2650)(-825 2400);
WIRE 16 -1 (-2000 5100)(-2000 4925);
WIRE 16 -1 (-1975 4925)(-2000 4925);
WIRE 16 -1 (-2000 4925)(-2200 4925);
WIRE 16 -1 (-1275 4925)(-1975 4925);
FORCEPROP 2 LAST SIG_NAME GPU_3V3IO_RSVD1
J 0
(-1935 4935);
DISPLAY 0.808511 (-1935 4935);
WIRE 16 -1 (-1975 4825)(-1975 4925);
WIRE 16 -1 (-1275 4925)(-1275 6050);
WIRE 16 -1 (-1075 4925)(-1275 4925);
WIRE 16 -1 (-750 6050)(-1275 6050);
WIRE 16 -1 (-825 1025)(-825 775);
WIRE 16 -1 (75 775)(-825 775);
FORCEPROP 2 LAST SIG_NAME HGX_DETECT
J 0
(-760 785);
DISPLAY 0.808511 (-760 785);
FORCEPROP 2 LASTPROP $XRERR UNIQUE?
J 0
(-1000 785);
DISPLAY 0.638298 (-1000 785);
PAINT MONO (-1000 785);
DISPLAY INVISIBLE (-1000 785);
WIRE 16 -1 (-825 725)(-825 775);
WIRE 16 -1 (325 1150)(325 1075);
WIRE 16 -1 (1100 1075)(325 1075);
FORCEPROP 2 LAST SIG_NAME HGX_DETECT_N_ISO
J 0
(390 1085);
DISPLAY 0.808511 (390 1085);
WIRE 16 -1 (325 1075)(325 1025);
WIRE 16 -1 (1400 1075)(1100 1075);
WIRE 16 -1 (1100 875)(1100 1075);
WIRE 16 -1 (-1975 375)(-1975 475);
WIRE 16 -1 (-1075 475)(-1975 475);
FORCEPROP 2 LAST SIG_NAME HGX_DETECT_N
J 0
(-1935 485);
DISPLAY 0.808511 (-1935 485);
WIRE 16 -1 (-1975 475)(-2000 475);
WIRE 16 -1 (-2000 650)(-2000 475);
WIRE 16 -1 (-2000 475)(-2200 475);
WIRE 16 -1 (4000 5575)(4100 5575);
WIRE 16 -1 (4000 5575)(4000 5025);
WIRE 16 -1 (4100 5575)(4100 5625);
WIRE 16 -1 (4100 5525)(4100 5575);
WIRE 16 -1 (325 5600)(325 5525);
WIRE 16 -1 (325 5525)(1100 5525);
FORCEPROP 2 LAST SIG_NAME GPU_3V3IO_RSVD1_ISO
J 0
(390 5535);
DISPLAY 0.808511 (390 5535);
WIRE 16 -1 (325 5525)(325 5475);
WIRE 16 -1 (1125 5525)(1100 5525);
WIRE 16 -1 (1100 5325)(1100 5525);
WIRE 16 -1 (1125 6050)(1125 5525);
WIRE 16 -1 (1400 5525)(1125 5525);
WIRE 16 -1 (-550 6050)(1125 6050);
WIRE 16 -1 (1150 4150)(1125 4150);
WIRE 16 -1 (1425 4150)(1150 4150);
WIRE 16 -1 (1150 4575)(1150 4150);
WIRE 16 -1 (1125 4150)(350 4150);
FORCEPROP 2 LAST SIG_NAME GPU_3V3IO_RSVD3_ISO
J 0
(415 4160);
DISPLAY 0.808511 (415 4160);
WIRE 16 -1 (1125 3950)(1125 4150);
WIRE 16 -1 (350 4225)(350 4150);
WIRE 16 -1 (350 4150)(350 4100);
WIRE 16 -1 (-325 4575)(1150 4575);
WIRE 16 -1 (325 2775)(325 2700);
WIRE 16 -1 (1100 2700)(325 2700);
FORCEPROP 2 LAST SIG_NAME GPU_3V3IO_RSVD4_ISO
J 0
(390 2710);
DISPLAY 0.808511 (390 2710);
WIRE 16 -1 (325 2700)(325 2650);
WIRE 16 -1 (1175 2700)(1100 2700);
WIRE 16 -1 (1100 2500)(1100 2700);
WIRE 16 -1 (1175 3125)(1175 2700);
WIRE 16 -1 (1400 2700)(1175 2700);
WIRE 16 -1 (-325 3125)(1175 3125);
WIRE 16 -1 (5125 5275)(4400 5275);
FORCEPROP 2 LAST SIG_NAME SWB_HSC_EN_BUF_R
J 0
(4440 5285);
DISPLAY 0.808511 (4440 5285);
FORCEPROP 2 LASTPROP $XRERR UNIQUE?
J 0
(4200 5285);
DISPLAY 0.638298 (4200 5285);
PAINT MONO (4200 5285);
DISPLAY INVISIBLE (4200 5285);
WIRE 16 -1 (5125 5425)(5125 5275);
WIRE 16 -1 (5125 5275)(5175 5275);
WIRE 16 -1 (4400 5275)(4400 4725);
WIRE 16 -1 (4400 4725)(4350 4725);
WIRE 16 -1 (5175 5275)(5275 5275);
WIRE 16 -1 (5175 5100)(5175 5275);
WIRE 16 -1 (6150 5275)(5475 5275);
FORCEPROP 2 LAST SIG_NAME SWB_HSC_EN_BUF
J 0
(5665 5285);
DISPLAY 0.808511 (5665 5285);
WIRE 16 -1 (5050 4475)(4350 4475);
FORCEPROP 2 LAST SIG_NAME NC_U316_2Y
J 0
(4615 4485);
DISPLAY 0.808511 (4615 4485);
FORCEPROP 2 LASTPROP $XRERR UNIQUE?
J 0
(5080 4475);
DISPLAY 0.638298 (5080 4475);
PAINT MONO (5080 4475);
DISPLAY INVISIBLE (5080 4475);
WIRE 16 -1 (-825 5475)(-825 5225);
WIRE 16 -1 (75 5225)(-825 5225);
FORCEPROP 2 LAST SIG_NAME GPU_3V3IO_RSVD1_N
J 0
(-760 5235);
DISPLAY 0.808511 (-760 5235);
FORCEPROP 2 LASTPROP $XRERR UNIQUE?
J 0
(-1000 5235);
DISPLAY 0.638298 (-1000 5235);
PAINT MONO (-1000 5235);
DISPLAY INVISIBLE (-1000 5235);
WIRE 16 -1 (-825 5175)(-825 5225);
WIRE 16 -1 (-1300 3125)(-525 3125);
WIRE 16 -1 (-1300 2100)(-1300 3125);
WIRE 16 -1 (-1075 2100)(-1300 2100);
WIRE 16 -1 (-1300 2100)(-1975 2100);
FORCEPROP 2 LAST SIG_NAME GPU_3V3IO_RSVD4
J 0
(-1935 2110);
DISPLAY 0.808511 (-1935 2110);
WIRE 16 -1 (-1975 2100)(-2000 2100);
WIRE 16 -1 (-1975 2000)(-1975 2100);
WIRE 16 -1 (-2000 2275)(-2000 2100);
WIRE 16 -1 (-2000 2100)(-2200 2100);
WIRE 16 -1 (-525 4575)(-1250 4575);
WIRE 16 -1 (-1250 3550)(-1250 4575);
WIRE 16 -1 (-1050 3550)(-1250 3550);
WIRE 16 -1 (-1250 3550)(-1950 3550);
FORCEPROP 2 LAST SIG_NAME GPU_3V3IO_RSVD3
J 0
(-1910 3560);
DISPLAY 0.808511 (-1910 3560);
WIRE 16 -1 (-1950 3550)(-1975 3550);
WIRE 16 -1 (-1950 3450)(-1950 3550);
WIRE 16 -1 (-1975 3725)(-1975 3550);
WIRE 16 -1 (-1975 3550)(-2175 3550);
WIRE 16 -1 (-800 4100)(-800 3850);
WIRE 16 -1 (100 3850)(-800 3850);
FORCEPROP 2 LAST SIG_NAME GPU_3V3IO_RSVD3_N
J 0
(-735 3860);
DISPLAY 0.808511 (-735 3860);
FORCEPROP 2 LASTPROP $XRERR UNIQUE?
J 0
(-975 3860);
DISPLAY 0.638298 (-975 3860);
PAINT MONO (-975 3860);
DISPLAY INVISIBLE (-975 3860);
WIRE 16 -1 (-800 3800)(-800 3850);
WIRE 16 -1 (2250 5275)(2375 5275);
WIRE 16 -1 (2375 5275)(2375 5450);
WIRE 16 -1 (2375 5275)(2400 5275);
WIRE 16 -1 (2400 5275)(3550 5275);
FORCEPROP 2 LAST SIG_NAME SWB_HSC_EN
J 0
(2515 5285);
DISPLAY 0.808511 (2515 5285);
WIRE 16 -1 (2400 5175)(2400 5275);
WIRE 16 -1 (3550 5275)(3550 4725);
WIRE 16 -1 (3550 4725)(3600 4725);
DOT 1 (1175 2700);
DOT 1 (-1300 2100);
DOT 1 (-1950 3550);
DOT 1 (1125 5525);
DOT 1 (1100 5525);
DOT 1 (1150 4150);
DOT 1 (1125 4150);
DOT 1 (-1250 3550);
DOT 1 (-1275 4925);
DOT 1 (2400 5275);
DOT 1 (2375 5275);
DOT 1 (4100 5575);
DOT 1 (5125 5275);
DOT 1 (5175 5275);
DOT 1 (-2000 475);
DOT 1 (-800 3850);
DOT 1 (325 5525);
DOT 1 (-825 5225);
DOT 1 (-2000 4925);
DOT 1 (-1975 3550);
DOT 1 (-1975 4925);
DOT 1 (-2000 2100);
DOT 1 (-1975 2100);
DOT 1 (-825 2400);
DOT 1 (325 2700);
DOT 1 (1100 2700);
DOT 1 (-1975 475);
DOT 1 (-825 775);
DOT 1 (325 1075);
DOT 1 (1100 1075);
DOT 1 (350 4150);
FORCENOTE
PUSH-PULL OUTPUT
(3650 3675) 0;
DISPLAY LEFT (3650 3675);
DISPLAY 1.021277 (3650 3675);
PAINT WHITE (3650 3675);
QUIT
